FILE_TYPE = MACRO_DRAWING;
SET COLOR_WIRE YELLOW;
SET COLOR_PROP ORANGE;
SET COLOR_DOT WHITE;
SET COLOR_ARC YELLOW;
SET COLOR_BODY GREEN;
SET COLOR_NOTE PURPLE;
SET PROP_DISPLAY VALUE;
SET PAGE_NUMBER P359;
FORCEADD UNIVERSAL_POWER..1
(2550 800);
FORCEPROP 3 LASTPIN (2550 750) SIG_NAME P3V3_AUX\g
J 0
(2560 760);
DISPLAY 0.659574 (2560 760);
PAINT MONO (2560 760);
DISPLAY INVISIBLE (2560 760);
FORCEPROP 1 LAST HDL_POWER P3V3_AUX
J 1
(2550 850);
DISPLAY 0.872340 (2550 850);
PAINT GREEN (2550 850);
FORCEPROP 2 LAST CDS_LIB pure_quanta_power
J 0
(2550 800);
DISPLAY INVISIBLE (2550 800);
FORCEPROP 1 LAST PATH I100
J 0
(2600 825);
DISPLAY 0.872340 (2600 825);
PAINT AQUA (2600 825);
DISPLAY INVISIBLE (2600 825);
FORCEADD Q_RES..2
(3900 125);
FORCEPROP 1 LAST LOCATION R4188
J 0
(3945 250);
DISPLAY 0.638298 (3945 250);
FORCEPROP 0 LAST $SEC 1
J 0
(3950 300);
DISPLAY 0.680851 (3950 300);
PAINT MONO (3950 300);
DISPLAY INVISIBLE (3950 300);
FORCEPROP 0 LAST CDS_SEC 1
J 0
(3950 300);
DISPLAY 1.021277 (3950 300);
DISPLAY INVISIBLE (3950 300);
FORCEPROP 1 LASTPIN (3900 225) $PN 1
J 0
(3905 187);
DISPLAY 0.787234 (3905 187);
PAINT MONO (3905 187);
FORCEPROP 1 LASTPIN (3900 25) $PN 2
J 0
(3905 35);
DISPLAY 0.787234 (3905 35);
PAINT MONO (3905 35);
FORCEPROP 1 LAST PACK_TYPE 0402LF
J 0
(3940 0);
DISPLAY 0.638298 (3940 0);
FORCEPROP 1 LAST MATERIAL EMPTY
J 0
(3940 50);
DISPLAY 0.638298 (3940 50);
PAINT RED (3940 50);
FORCEPROP 1 LAST VALUE 1K
J 0
(3945 200);
DISPLAY 0.638298 (3945 200);
FORCEPROP 1 LAST WATTAGE 1/16W
J 0
(3940 100);
DISPLAY 0.638298 (3940 100);
FORCEPROP 1 LAST TOLERANCE 1%
J 0
(3945 150);
DISPLAY 0.638298 (3945 150);
FORCEPROP 2 LAST CDS_LIB pure_quanta
J 0
(3900 125);
DISPLAY INVISIBLE (3900 125);
FORCEPROP 1 LAST PATH I101
J 0
(3950 300);
DISPLAY 0.978723 (3950 300);
PAINT WHITE (3950 300);
DISPLAY INVISIBLE (3950 300);
FORCEPROP 1 LAST PART_NUMBER CS21002FB06
J 0
(3940 -50);
DISPLAY 0.638298 (3940 -50);
DISPLAY INVISIBLE (3940 -50);
FORCEADD Q_RES..2
(3900 -475);
FORCEPROP 1 LAST LOCATION R4189
J 0
(3945 -350);
DISPLAY 0.638298 (3945 -350);
FORCEPROP 0 LAST $SEC 1
J 0
(3950 -300);
DISPLAY 0.680851 (3950 -300);
PAINT MONO (3950 -300);
DISPLAY INVISIBLE (3950 -300);
FORCEPROP 0 LAST CDS_SEC 1
J 0
(3950 -300);
DISPLAY 1.021277 (3950 -300);
DISPLAY INVISIBLE (3950 -300);
FORCEPROP 1 LASTPIN (3900 -375) $PN 1
J 0
(3905 -413);
DISPLAY 0.787234 (3905 -413);
PAINT MONO (3905 -413);
FORCEPROP 1 LASTPIN (3900 -575) $PN 2
J 0
(3905 -565);
DISPLAY 0.787234 (3905 -565);
PAINT MONO (3905 -565);
FORCEPROP 1 LAST TOLERANCE 1%
J 0
(3945 -450);
DISPLAY 0.638298 (3945 -450);
FORCEPROP 1 LAST WATTAGE 1/16W
J 0
(3940 -500);
DISPLAY 0.638298 (3940 -500);
FORCEPROP 1 LAST VALUE 1K
J 0
(3945 -400);
DISPLAY 0.638298 (3945 -400);
FORCEPROP 1 LAST PACK_TYPE 0402LF
J 0
(3940 -600);
DISPLAY 0.638298 (3940 -600);
FORCEPROP 1 LAST MATERIAL CHIP
J 0
(3940 -550);
DISPLAY 0.638298 (3940 -550);
FORCEPROP 2 LAST CDS_LIB pure_quanta
J 0
(3900 -475);
DISPLAY INVISIBLE (3900 -475);
FORCEPROP 1 LAST PATH I102
J 0
(3950 -300);
DISPLAY 0.978723 (3950 -300);
PAINT WHITE (3950 -300);
DISPLAY INVISIBLE (3950 -300);
FORCEPROP 1 LAST PART_NUMBER CS21002FB06
J 0
(3940 -650);
DISPLAY 0.638298 (3940 -650);
DISPLAY INVISIBLE (3940 -650);
FORCEADD UNIVERSAL_GND..1
(3900 -700);
FORCEPROP 3 LASTPIN (3900 -650) SIG_NAME GND\g
J 0
(3910 -640);
DISPLAY 0.659574 (3910 -640);
PAINT MONO (3910 -640);
DISPLAY INVISIBLE (3910 -640);
FORCEPROP 2 LAST CDS_LIB pure_quanta_power
J 0
(3900 -700);
PAINT MONO (3900 -700);
DISPLAY INVISIBLE (3900 -700);
FORCEPROP 1 LAST HDL_POWER GND
J 1
(3925 -775);
DISPLAY 0.872340 (3925 -775);
PAINT GREEN (3925 -775);
DISPLAY INVISIBLE (3925 -775);
FORCEPROP 1 LAST PATH I103
J 0
(3975 -700);
DISPLAY 0.872340 (3975 -700);
PAINT AQUA (3975 -700);
DISPLAY INVISIBLE (3975 -700);
FORCEADD Q_CAP..1
R 2
(2550 475);
FORCEPROP 1 LAST LOCATION C73
J 2
(2500 575);
DISPLAY 0.978723 (2500 575);
FORCEPROP 0 LAST $SEC 1
J 0
(2500 625);
DISPLAY 0.680851 (2500 625);
PAINT MONO (2500 625);
DISPLAY INVISIBLE (2500 625);
FORCEPROP 0 LAST CDS_SEC 1
J 0
(2500 625);
DISPLAY 1.021277 (2500 625);
DISPLAY INVISIBLE (2500 625);
FORCEPROP 1 LASTPIN (2550 575) $PN 1
J 2
(2540 555);
DISPLAY 0.787234 (2540 555);
PAINT MONO (2540 555);
FORCEPROP 1 LASTPIN (2550 375) $PN 2
J 2
(2540 355);
DISPLAY 0.787234 (2540 355);
PAINT MONO (2540 355);
FORCEPROP 1 LAST VOLTAGE 25V
J 2
(2500 475);
DISPLAY 0.510638 (2500 475);
FORCEPROP 1 LAST MATERIAL X7R
J 2
(2500 375);
DISPLAY 0.510638 (2500 375);
FORCEPROP 1 LAST PACK_TYPE 0402
J 2
(2500 275);
DISPLAY 0.510638 (2500 275);
FORCEPROP 1 LAST VALUE 0.1UF
J 2
(2500 525);
DISPLAY 0.510638 (2500 525);
FORCEPROP 1 LAST TOLERANCE 10%
J 2
(2500 425);
DISPLAY 0.510638 (2500 425);
FORCEPROP 2 LAST CDS_LIB pure_quanta
J 0
(2550 475);
DISPLAY INVISIBLE (2550 475);
FORCEPROP 1 LAST PATH I104
J 2
(2500 625);
DISPLAY 0.978723 (2500 625);
PAINT WHITE (2500 625);
DISPLAY INVISIBLE (2500 625);
FORCEPROP 1 LAST PART_NUMBER CH4104K1B00
J 2
(2500 325);
DISPLAY 0.510638 (2500 325);
DISPLAY INVISIBLE (2500 325);
FORCEADD UNIVERSAL_GND..1
(2550 250);
FORCEPROP 3 LASTPIN (2550 300) SIG_NAME GND\g
J 0
(2560 310);
DISPLAY 0.659574 (2560 310);
PAINT MONO (2560 310);
DISPLAY INVISIBLE (2560 310);
FORCEPROP 2 LAST CDS_LIB pure_quanta_power
J 0
(2550 250);
DISPLAY INVISIBLE (2550 250);
FORCEPROP 1 LAST HDL_POWER GND
J 1
(2575 175);
DISPLAY 0.872340 (2575 175);
PAINT GREEN (2575 175);
DISPLAY INVISIBLE (2575 175);
FORCEPROP 1 LAST PATH I105
J 0
(2625 250);
DISPLAY 0.872340 (2625 250);
PAINT AQUA (2625 250);
DISPLAY INVISIBLE (2625 250);
FORCEADD UNIVERSAL_GND..1
(1625 -450);
FORCEPROP 3 LASTPIN (1625 -400) SIG_NAME GND\g
J 0
(1635 -390);
DISPLAY 0.659574 (1635 -390);
PAINT MONO (1635 -390);
DISPLAY INVISIBLE (1635 -390);
FORCEPROP 2 LAST CDS_LIB pure_quanta_power
J 0
(1625 -450);
DISPLAY INVISIBLE (1625 -450);
FORCEPROP 1 LAST HDL_POWER GND
J 1
(1650 -525);
DISPLAY 0.872340 (1650 -525);
PAINT GREEN (1650 -525);
DISPLAY INVISIBLE (1650 -525);
FORCEPROP 1 LAST PATH I106
J 0
(1700 -450);
DISPLAY 0.872340 (1700 -450);
PAINT AQUA (1700 -450);
DISPLAY INVISIBLE (1700 -450);
FORCEADD Q_RES..1
(300 125);
FORCEPROP 1 LAST LOCATION R4182
J 0
(100 125);
DISPLAY 0.638298 (100 125);
FORCEPROP 0 LAST $SEC 1
J 0
(650 175);
DISPLAY 0.680851 (650 175);
PAINT MONO (650 175);
DISPLAY INVISIBLE (650 175);
FORCEPROP 0 LAST CDS_SEC 1
J 0
(650 175);
DISPLAY 1.021277 (650 175);
DISPLAY INVISIBLE (650 175);
FORCEPROP 1 LASTPIN (200 125) $PN 1
J 0
(212 137);
DISPLAY 0.787234 (212 137);
PAINT MONO (212 137);
FORCEPROP 1 LASTPIN (400 125) $PN 2
J 0
(362 137);
DISPLAY 0.787234 (362 137);
PAINT MONO (362 137);
FORCEPROP 1 LAST PACK_TYPE 0402LF
J 0
(650 125);
DISPLAY 0.638298 (650 125);
FORCEPROP 1 LAST VALUE 33.2
J 2
(525 125);
DISPLAY 0.638298 (525 125);
FORCEPROP 1 LAST TOLERANCE 1%
J 0
(550 125);
DISPLAY 0.638298 (550 125);
FORCEPROP 1 LAST MATERIAL CHIP
J 0
(-25 125);
DISPLAY 0.638298 (-25 125);
FORCEPROP 1 LAST WATTAGE 1/16W
J 2
(-50 125);
DISPLAY 0.638298 (-50 125);
FORCEPROP 2 LAST CDS_LIB pure_quanta
J 0
(300 125);
DISPLAY INVISIBLE (300 125);
FORCEPROP 1 LAST PATH I107
J 0
(250 275);
DISPLAY 0.978723 (250 275);
PAINT WHITE (250 275);
DISPLAY INVISIBLE (250 275);
FORCEPROP 1 LAST PART_NUMBER CS03322FB03
J 0
(175 225);
DISPLAY 0.638298 (175 225);
DISPLAY INVISIBLE (175 225);
FORCEADD Q_RES..1
(300 -175);
FORCEPROP 1 LAST LOCATION R4214
J 0
(100 -175);
DISPLAY 0.638298 (100 -175);
FORCEPROP 0 LAST $SEC 1
J 0
(600 -125);
DISPLAY 0.680851 (600 -125);
PAINT MONO (600 -125);
DISPLAY INVISIBLE (600 -125);
FORCEPROP 0 LAST CDS_SEC 1
J 0
(600 -125);
DISPLAY 1.021277 (600 -125);
DISPLAY INVISIBLE (600 -125);
FORCEPROP 1 LASTPIN (200 -175) $PN 1
J 0
(212 -163);
DISPLAY 0.787234 (212 -163);
PAINT MONO (212 -163);
FORCEPROP 1 LASTPIN (400 -175) $PN 2
J 0
(362 -163);
DISPLAY 0.787234 (362 -163);
PAINT MONO (362 -163);
FORCEPROP 1 LAST MATERIAL CHIP
J 0
(475 -175);
DISPLAY 0.574468 (475 -175);
FORCEPROP 1 LAST PACK_TYPE 0402LF
J 0
(600 -175);
DISPLAY 0.574468 (600 -175);
FORCEPROP 1 LAST VALUE 0
J 2
(450 -175);
DISPLAY 0.574468 (450 -175);
FORCEPROP 1 LAST TOLERANCE 5%
J 0
(100 -250);
DISPLAY 0.723404 (100 -250);
PAINT SKYBLUE (100 -250);
DISPLAY INVISIBLE (100 -250);
FORCEPROP 1 LAST WATTAGE 1/16W
J 2
(375 -250);
DISPLAY 0.723404 (375 -250);
PAINT SKYBLUE (375 -250);
DISPLAY INVISIBLE (375 -250);
FORCEPROP 2 LAST CDS_LIB pure_quanta
J 0
(300 -175);
DISPLAY INVISIBLE (300 -175);
FORCEPROP 1 LAST PATH I108
J 0
(250 -25);
DISPLAY 0.978723 (250 -25);
PAINT WHITE (250 -25);
DISPLAY INVISIBLE (250 -25);
FORCEPROP 1 LAST PART_NUMBER CS00002JB13
J 0
(25 -300);
DISPLAY 0.723404 (25 -300);
PAINT WHITE (25 -300);
DISPLAY INVISIBLE (25 -300);
FORCEADD Q_RES..1
(300 -25);
FORCEPROP 1 LAST LOCATION R4179
J 0
(100 -25);
DISPLAY 0.638298 (100 -25);
FORCEPROP 0 LAST $SEC 1
J 0
(650 25);
DISPLAY 0.680851 (650 25);
PAINT MONO (650 25);
DISPLAY INVISIBLE (650 25);
FORCEPROP 0 LAST CDS_SEC 1
J 0
(650 25);
DISPLAY 1.021277 (650 25);
DISPLAY INVISIBLE (650 25);
FORCEPROP 1 LASTPIN (200 -25) $PN 1
J 0
(212 -13);
DISPLAY 0.787234 (212 -13);
PAINT MONO (212 -13);
FORCEPROP 1 LASTPIN (400 -25) $PN 2
J 0
(362 -13);
DISPLAY 0.787234 (362 -13);
PAINT MONO (362 -13);
FORCEPROP 1 LAST PACK_TYPE 0402LF
J 0
(650 -25);
DISPLAY 0.638298 (650 -25);
FORCEPROP 1 LAST WATTAGE 1/16W
J 2
(-50 -25);
DISPLAY 0.638298 (-50 -25);
FORCEPROP 1 LAST TOLERANCE 1%
J 0
(550 -25);
DISPLAY 0.638298 (550 -25);
FORCEPROP 1 LAST VALUE 33.2
J 2
(525 -25);
DISPLAY 0.638298 (525 -25);
FORCEPROP 1 LAST MATERIAL CHIP
J 0
(-25 -25);
DISPLAY 0.638298 (-25 -25);
FORCEPROP 2 LAST CDS_LIB pure_quanta
J 0
(300 -25);
DISPLAY INVISIBLE (300 -25);
FORCEPROP 1 LAST PATH I109
J 0
(250 125);
DISPLAY 0.978723 (250 125);
PAINT WHITE (250 125);
DISPLAY INVISIBLE (250 125);
FORCEPROP 1 LAST PART_NUMBER CS03322FB03
J 0
(150 200);
DISPLAY 0.638298 (150 200);
DISPLAY INVISIBLE (150 200);
FORCEADD OFFPAGE..1
(-950 125);
FORCEPROP 2 LAST $XR0 253 
J 0
(-1232 125);
DISPLAY 0.638298 (-1232 125);
PAINT MONO (-1232 125);
FORCEPROP 2 LAST CDS_LIB standard
J 0
(-950 125);
DISPLAY INVISIBLE (-950 125);
FORCEPROP 1 LAST OFFPAGE TRUE
J 0
(-625 0);
DISPLAY 0.872340 (-625 0);
PAINT GREEN (-625 0);
DISPLAY INVISIBLE (-625 0);
FORCEPROP 1 LAST COMMENT_BODY TRUE
J 0
(-825 25);
DISPLAY 0.872340 (-825 25);
PAINT GREEN (-825 25);
DISPLAY INVISIBLE (-825 25);
FORCEPROP 2 LAST PATH I110
J 0
(-1125 175);
DISPLAY 1.021277 (-1125 175);
DISPLAY INVISIBLE (-1125 175);
FORCEADD OFFPAGE..3
R 2
(-950 -25);
FORCEPROP 2 LAST $XR0 253 
J 0
(-1230 -25);
DISPLAY 0.638298 (-1230 -25);
PAINT MONO (-1230 -25);
FORCEPROP 2 LAST CDS_LIB standard
J 0
(-950 -25);
DISPLAY INVISIBLE (-950 -25);
FORCEPROP 1 LAST OFFPAGE TRUE
J 2
(-1275 -150);
DISPLAY 0.872340 (-1275 -150);
DISPLAY INVISIBLE (-1275 -150);
FORCEPROP 1 LAST COMMENT_BODY TRUE
J 2
(-900 -125);
DISPLAY 0.872340 (-900 -125);
PAINT GREEN (-900 -125);
DISPLAY INVISIBLE (-900 -125);
FORCEPROP 2 LAST PATH I111
J 0
(-1150 25);
DISPLAY 1.021277 (-1150 25);
DISPLAY INVISIBLE (-1150 25);
FORCEADD OFFPAGE..3
R 2
(-975 -1500);
FORCEPROP 2 LAST $XR0 253 
J 0
(-1285 -1500);
DISPLAY 0.638298 (-1285 -1500);
PAINT MONO (-1285 -1500);
FORCEPROP 2 LAST CDS_LIB standard
J 0
(-975 -1500);
DISPLAY INVISIBLE (-975 -1500);
FORCEPROP 1 LAST OFFPAGE TRUE
J 2
(-1300 -1625);
DISPLAY 0.872340 (-1300 -1625);
DISPLAY INVISIBLE (-1300 -1625);
FORCEPROP 1 LAST COMMENT_BODY TRUE
J 2
(-925 -1600);
DISPLAY 0.872340 (-925 -1600);
PAINT GREEN (-925 -1600);
DISPLAY INVISIBLE (-925 -1600);
FORCEPROP 2 LAST PATH I112
J 0
(-1175 -1450);
DISPLAY 1.021277 (-1175 -1450);
DISPLAY INVISIBLE (-1175 -1450);
FORCEADD OFFPAGE..1
(-975 -1350);
FORCEPROP 2 LAST $XR0 253 
J 0
(-1257 -1350);
DISPLAY 0.638298 (-1257 -1350);
PAINT MONO (-1257 -1350);
FORCEPROP 2 LAST CDS_LIB standard
J 0
(-975 -1350);
DISPLAY INVISIBLE (-975 -1350);
FORCEPROP 1 LAST OFFPAGE TRUE
J 0
(-650 -1475);
DISPLAY 0.872340 (-650 -1475);
PAINT GREEN (-650 -1475);
DISPLAY INVISIBLE (-650 -1475);
FORCEPROP 1 LAST COMMENT_BODY TRUE
J 0
(-850 -1450);
DISPLAY 0.872340 (-850 -1450);
PAINT GREEN (-850 -1450);
DISPLAY INVISIBLE (-850 -1450);
FORCEPROP 2 LAST PATH I113
J 0
(-1150 -1300);
DISPLAY 1.021277 (-1150 -1300);
DISPLAY INVISIBLE (-1150 -1300);
FORCEADD Q_RES..1
(275 -1500);
FORCEPROP 1 LAST LOCATION R4178
J 0
(75 -1500);
DISPLAY 0.638298 (75 -1500);
FORCEPROP 0 LAST $SEC 1
J 0
(625 -1450);
DISPLAY 0.680851 (625 -1450);
PAINT MONO (625 -1450);
DISPLAY INVISIBLE (625 -1450);
FORCEPROP 0 LAST CDS_SEC 1
J 0
(625 -1450);
DISPLAY 1.021277 (625 -1450);
DISPLAY INVISIBLE (625 -1450);
FORCEPROP 1 LASTPIN (175 -1500) $PN 1
J 0
(187 -1488);
DISPLAY 0.787234 (187 -1488);
PAINT MONO (187 -1488);
FORCEPROP 1 LASTPIN (375 -1500) $PN 2
J 0
(337 -1488);
DISPLAY 0.787234 (337 -1488);
PAINT MONO (337 -1488);
FORCEPROP 1 LAST VALUE 33.2
J 2
(500 -1500);
DISPLAY 0.638298 (500 -1500);
FORCEPROP 1 LAST PACK_TYPE 0402LF
J 0
(625 -1500);
DISPLAY 0.638298 (625 -1500);
FORCEPROP 1 LAST MATERIAL CHIP
J 0
(-50 -1500);
DISPLAY 0.638298 (-50 -1500);
FORCEPROP 1 LAST WATTAGE 1/16W
J 2
(-75 -1500);
DISPLAY 0.638298 (-75 -1500);
FORCEPROP 1 LAST TOLERANCE 1%
J 0
(525 -1500);
DISPLAY 0.638298 (525 -1500);
FORCEPROP 2 LAST CDS_LIB pure_quanta
J 0
(275 -1500);
DISPLAY INVISIBLE (275 -1500);
FORCEPROP 1 LAST PATH I114
J 0
(225 -1350);
DISPLAY 0.978723 (225 -1350);
PAINT WHITE (225 -1350);
DISPLAY INVISIBLE (225 -1350);
FORCEPROP 1 LAST PART_NUMBER CS03322FB03
J 0
(100 -1300);
DISPLAY 0.638298 (100 -1300);
DISPLAY INVISIBLE (100 -1300);
FORCEADD Q_RES..1
(275 -1650);
FORCEPROP 1 LAST LOCATION R4213
J 0
(75 -1650);
DISPLAY 0.638298 (75 -1650);
FORCEPROP 0 LAST $SEC 1
J 0
(575 -1600);
DISPLAY 0.680851 (575 -1600);
PAINT MONO (575 -1600);
DISPLAY INVISIBLE (575 -1600);
FORCEPROP 0 LAST CDS_SEC 1
J 0
(575 -1600);
DISPLAY 1.021277 (575 -1600);
DISPLAY INVISIBLE (575 -1600);
FORCEPROP 1 LASTPIN (175 -1650) $PN 1
J 0
(187 -1638);
DISPLAY 0.787234 (187 -1638);
PAINT MONO (187 -1638);
FORCEPROP 1 LASTPIN (375 -1650) $PN 2
J 0
(337 -1638);
DISPLAY 0.787234 (337 -1638);
PAINT MONO (337 -1638);
FORCEPROP 1 LAST PACK_TYPE 0402LF
J 0
(575 -1650);
DISPLAY 0.574468 (575 -1650);
FORCEPROP 1 LAST VALUE 0
J 2
(425 -1650);
DISPLAY 0.574468 (425 -1650);
FORCEPROP 1 LAST MATERIAL CHIP
J 0
(450 -1650);
DISPLAY 0.574468 (450 -1650);
FORCEPROP 2 LAST CDS_LIB pure_quanta
J 0
(275 -1650);
DISPLAY INVISIBLE (275 -1650);
FORCEPROP 1 LAST WATTAGE 1/16W
J 2
(350 -1725);
DISPLAY 0.723404 (350 -1725);
PAINT SKYBLUE (350 -1725);
DISPLAY INVISIBLE (350 -1725);
FORCEPROP 1 LAST TOLERANCE 5%
J 0
(75 -1725);
DISPLAY 0.723404 (75 -1725);
PAINT SKYBLUE (75 -1725);
DISPLAY INVISIBLE (75 -1725);
FORCEPROP 1 LAST PATH I115
J 0
(225 -1500);
DISPLAY 0.978723 (225 -1500);
PAINT WHITE (225 -1500);
DISPLAY INVISIBLE (225 -1500);
FORCEPROP 1 LAST PART_NUMBER CS00002JB13
J 0
(0 -1775);
DISPLAY 0.723404 (0 -1775);
PAINT WHITE (0 -1775);
DISPLAY INVISIBLE (0 -1775);
FORCEADD Q_RES..1
(275 -1350);
FORCEPROP 1 LAST LOCATION R4181
J 0
(75 -1350);
DISPLAY 0.638298 (75 -1350);
FORCEPROP 0 LAST $SEC 1
J 0
(625 -1300);
DISPLAY 0.680851 (625 -1300);
PAINT MONO (625 -1300);
DISPLAY INVISIBLE (625 -1300);
FORCEPROP 0 LAST CDS_SEC 1
J 0
(625 -1300);
DISPLAY 1.021277 (625 -1300);
DISPLAY INVISIBLE (625 -1300);
FORCEPROP 1 LASTPIN (175 -1350) $PN 1
J 0
(187 -1338);
DISPLAY 0.787234 (187 -1338);
PAINT MONO (187 -1338);
FORCEPROP 1 LASTPIN (375 -1350) $PN 2
J 0
(337 -1338);
DISPLAY 0.787234 (337 -1338);
PAINT MONO (337 -1338);
FORCEPROP 1 LAST PACK_TYPE 0402LF
J 0
(625 -1350);
DISPLAY 0.638298 (625 -1350);
FORCEPROP 1 LAST WATTAGE 1/16W
J 2
(-75 -1350);
DISPLAY 0.638298 (-75 -1350);
FORCEPROP 1 LAST TOLERANCE 1%
J 0
(525 -1350);
DISPLAY 0.638298 (525 -1350);
FORCEPROP 1 LAST VALUE 33.2
J 2
(500 -1350);
DISPLAY 0.638298 (500 -1350);
FORCEPROP 1 LAST MATERIAL CHIP
J 0
(-50 -1350);
DISPLAY 0.638298 (-50 -1350);
FORCEPROP 2 LAST CDS_LIB pure_quanta
J 0
(275 -1350);
DISPLAY INVISIBLE (275 -1350);
FORCEPROP 1 LAST PATH I116
J 0
(225 -1200);
DISPLAY 0.978723 (225 -1200);
PAINT WHITE (225 -1200);
DISPLAY INVISIBLE (225 -1200);
FORCEPROP 1 LAST PART_NUMBER CS03322FB03
J 0
(150 -1250);
DISPLAY 0.638298 (150 -1250);
DISPLAY INVISIBLE (150 -1250);
FORCEADD UNIVERSAL_GND..1
(1600 -1925);
FORCEPROP 3 LASTPIN (1600 -1875) SIG_NAME GND\g
J 0
(1610 -1865);
DISPLAY 0.659574 (1610 -1865);
PAINT MONO (1610 -1865);
DISPLAY INVISIBLE (1610 -1865);
FORCEPROP 2 LAST CDS_LIB pure_quanta_power
J 0
(1600 -1925);
DISPLAY INVISIBLE (1600 -1925);
FORCEPROP 1 LAST HDL_POWER GND
J 1
(1625 -2000);
DISPLAY 0.872340 (1625 -2000);
PAINT GREEN (1625 -2000);
DISPLAY INVISIBLE (1625 -2000);
FORCEPROP 1 LAST PATH I117
J 0
(1675 -1925);
DISPLAY 0.872340 (1675 -1925);
PAINT AQUA (1675 -1925);
DISPLAY INVISIBLE (1675 -1925);
FORCEADD UNIVERSAL_GND..1
(2525 -1225);
FORCEPROP 3 LASTPIN (2525 -1175) SIG_NAME GND\g
J 0
(2535 -1165);
DISPLAY 0.659574 (2535 -1165);
PAINT MONO (2535 -1165);
DISPLAY INVISIBLE (2535 -1165);
FORCEPROP 2 LAST CDS_LIB pure_quanta_power
J 0
(2525 -1225);
DISPLAY INVISIBLE (2525 -1225);
FORCEPROP 1 LAST HDL_POWER GND
J 1
(2550 -1300);
DISPLAY 0.872340 (2550 -1300);
PAINT GREEN (2550 -1300);
DISPLAY INVISIBLE (2550 -1300);
FORCEPROP 1 LAST PATH I118
J 0
(2600 -1225);
DISPLAY 0.872340 (2600 -1225);
PAINT AQUA (2600 -1225);
DISPLAY INVISIBLE (2600 -1225);
FORCEADD Q_CAP..1
R 2
(2525 -1000);
FORCEPROP 1 LAST LOCATION C32
J 2
(2475 -900);
DISPLAY 0.978723 (2475 -900);
FORCEPROP 0 LAST $SEC 1
J 0
(2475 -850);
DISPLAY 0.680851 (2475 -850);
PAINT MONO (2475 -850);
DISPLAY INVISIBLE (2475 -850);
FORCEPROP 0 LAST CDS_SEC 1
J 0
(2475 -850);
DISPLAY 1.021277 (2475 -850);
DISPLAY INVISIBLE (2475 -850);
FORCEPROP 1 LASTPIN (2525 -900) $PN 1
J 2
(2515 -920);
DISPLAY 0.787234 (2515 -920);
PAINT MONO (2515 -920);
FORCEPROP 1 LASTPIN (2525 -1100) $PN 2
J 2
(2515 -1120);
DISPLAY 0.787234 (2515 -1120);
PAINT MONO (2515 -1120);
FORCEPROP 1 LAST PACK_TYPE 0402
J 2
(2475 -1200);
DISPLAY 0.510638 (2475 -1200);
FORCEPROP 1 LAST VALUE 0.1UF
J 2
(2475 -950);
DISPLAY 0.510638 (2475 -950);
FORCEPROP 1 LAST VOLTAGE 25V
J 2
(2475 -1000);
DISPLAY 0.510638 (2475 -1000);
FORCEPROP 1 LAST TOLERANCE 10%
J 2
(2475 -1050);
DISPLAY 0.510638 (2475 -1050);
FORCEPROP 1 LAST MATERIAL X7R
J 2
(2475 -1100);
DISPLAY 0.510638 (2475 -1100);
FORCEPROP 2 LAST CDS_LIB pure_quanta
J 0
(2525 -1000);
DISPLAY INVISIBLE (2525 -1000);
FORCEPROP 1 LAST PATH I119
J 2
(2475 -850);
DISPLAY 0.978723 (2475 -850);
PAINT WHITE (2475 -850);
DISPLAY INVISIBLE (2475 -850);
FORCEPROP 1 LAST PART_NUMBER CH4104K1B00
J 2
(2475 -1150);
DISPLAY 0.510638 (2475 -1150);
DISPLAY INVISIBLE (2475 -1150);
FORCEADD UNIVERSAL_GND..1
(3875 -2175);
FORCEPROP 3 LASTPIN (3875 -2125) SIG_NAME GND\g
J 0
(3885 -2115);
DISPLAY 0.659574 (3885 -2115);
PAINT MONO (3885 -2115);
DISPLAY INVISIBLE (3885 -2115);
FORCEPROP 2 LAST CDS_LIB pure_quanta_power
J 0
(3875 -2175);
PAINT MONO (3875 -2175);
DISPLAY INVISIBLE (3875 -2175);
FORCEPROP 1 LAST HDL_POWER GND
J 1
(3900 -2250);
DISPLAY 0.872340 (3900 -2250);
PAINT GREEN (3900 -2250);
DISPLAY INVISIBLE (3900 -2250);
FORCEPROP 1 LAST PATH I120
J 0
(3950 -2175);
DISPLAY 0.872340 (3950 -2175);
PAINT AQUA (3950 -2175);
DISPLAY INVISIBLE (3950 -2175);
FORCEADD Q_RES..2
(3875 -1950);
FORCEPROP 1 LAST LOCATION R4187
J 0
(3920 -1825);
DISPLAY 0.638298 (3920 -1825);
FORCEPROP 0 LAST $SEC 1
J 0
(3925 -1775);
DISPLAY 0.680851 (3925 -1775);
PAINT MONO (3925 -1775);
DISPLAY INVISIBLE (3925 -1775);
FORCEPROP 0 LAST CDS_SEC 1
J 0
(3925 -1775);
DISPLAY 1.021277 (3925 -1775);
DISPLAY INVISIBLE (3925 -1775);
FORCEPROP 1 LASTPIN (3875 -1850) $PN 1
J 0
(3880 -1888);
DISPLAY 0.787234 (3880 -1888);
PAINT MONO (3880 -1888);
FORCEPROP 1 LASTPIN (3875 -2050) $PN 2
J 0
(3880 -2040);
DISPLAY 0.787234 (3880 -2040);
PAINT MONO (3880 -2040);
FORCEPROP 1 LAST MATERIAL CHIP
J 0
(3915 -2025);
DISPLAY 0.638298 (3915 -2025);
FORCEPROP 1 LAST PACK_TYPE 0402LF
J 0
(3915 -2075);
DISPLAY 0.638298 (3915 -2075);
FORCEPROP 1 LAST VALUE 1K
J 0
(3920 -1875);
DISPLAY 0.638298 (3920 -1875);
FORCEPROP 1 LAST WATTAGE 1/16W
J 0
(3915 -1975);
DISPLAY 0.638298 (3915 -1975);
FORCEPROP 1 LAST TOLERANCE 1%
J 0
(3920 -1925);
DISPLAY 0.638298 (3920 -1925);
FORCEPROP 2 LAST CDS_LIB pure_quanta
J 0
(3875 -1950);
DISPLAY INVISIBLE (3875 -1950);
FORCEPROP 1 LAST PATH I121
J 0
(3925 -1775);
DISPLAY 0.978723 (3925 -1775);
PAINT WHITE (3925 -1775);
DISPLAY INVISIBLE (3925 -1775);
FORCEPROP 1 LAST PART_NUMBER CS21002FB06
J 0
(3915 -2125);
DISPLAY 0.638298 (3915 -2125);
DISPLAY INVISIBLE (3915 -2125);
FORCEADD Q_RES..2
(3875 -1350);
FORCEPROP 1 LAST LOCATION R4186
J 0
(3920 -1225);
DISPLAY 0.638298 (3920 -1225);
FORCEPROP 0 LAST $SEC 1
J 0
(3925 -1175);
DISPLAY 0.680851 (3925 -1175);
PAINT MONO (3925 -1175);
DISPLAY INVISIBLE (3925 -1175);
FORCEPROP 0 LAST CDS_SEC 1
J 0
(3925 -1175);
DISPLAY 1.021277 (3925 -1175);
DISPLAY INVISIBLE (3925 -1175);
FORCEPROP 1 LASTPIN (3875 -1250) $PN 1
J 0
(3880 -1288);
DISPLAY 0.787234 (3880 -1288);
PAINT MONO (3880 -1288);
FORCEPROP 1 LASTPIN (3875 -1450) $PN 2
J 0
(3880 -1440);
DISPLAY 0.787234 (3880 -1440);
PAINT MONO (3880 -1440);
FORCEPROP 1 LAST TOLERANCE 1%
J 0
(3920 -1325);
DISPLAY 0.638298 (3920 -1325);
FORCEPROP 1 LAST WATTAGE 1/16W
J 0
(3915 -1375);
DISPLAY 0.638298 (3915 -1375);
FORCEPROP 1 LAST VALUE 1K
J 0
(3920 -1275);
DISPLAY 0.638298 (3920 -1275);
FORCEPROP 1 LAST MATERIAL EMPTY
J 0
(3915 -1425);
DISPLAY 0.638298 (3915 -1425);
PAINT RED (3915 -1425);
FORCEPROP 1 LAST PACK_TYPE 0402LF
J 0
(3915 -1475);
DISPLAY 0.638298 (3915 -1475);
FORCEPROP 2 LAST CDS_LIB pure_quanta
J 0
(3875 -1350);
DISPLAY INVISIBLE (3875 -1350);
FORCEPROP 1 LAST PATH I122
J 0
(3925 -1175);
DISPLAY 0.978723 (3925 -1175);
PAINT WHITE (3925 -1175);
DISPLAY INVISIBLE (3925 -1175);
FORCEPROP 1 LAST PART_NUMBER CS21002FB06
J 0
(3915 -1525);
DISPLAY 0.638298 (3915 -1525);
DISPLAY INVISIBLE (3915 -1525);
FORCEADD UNIVERSAL_POWER..1
(2525 -675);
FORCEPROP 3 LASTPIN (2525 -725) SIG_NAME P3V3_AUX\g
J 0
(2535 -715);
DISPLAY 0.659574 (2535 -715);
PAINT MONO (2535 -715);
DISPLAY INVISIBLE (2535 -715);
FORCEPROP 1 LAST HDL_POWER P3V3_AUX
J 1
(2525 -625);
DISPLAY 0.872340 (2525 -625);
PAINT GREEN (2525 -625);
FORCEPROP 2 LAST CDS_LIB pure_quanta_power
J 0
(2525 -675);
DISPLAY INVISIBLE (2525 -675);
FORCEPROP 1 LAST PATH I123
J 0
(2575 -650);
DISPLAY 0.872340 (2575 -650);
PAINT AQUA (2575 -650);
DISPLAY INVISIBLE (2575 -650);
FORCEADD UNIVERSAL_GND..1
(4125 -2175);
FORCEPROP 3 LASTPIN (4125 -2125) SIG_NAME GND\g
J 0
(4135 -2115);
DISPLAY 0.659574 (4135 -2115);
PAINT MONO (4135 -2115);
DISPLAY INVISIBLE (4135 -2115);
FORCEPROP 2 LAST CDS_LIB pure_quanta_power
J 0
(4125 -2175);
PAINT MONO (4125 -2175);
DISPLAY INVISIBLE (4125 -2175);
FORCEPROP 1 LAST HDL_POWER GND
J 1
(4150 -2250);
DISPLAY 0.872340 (4150 -2250);
PAINT GREEN (4150 -2250);
DISPLAY INVISIBLE (4150 -2250);
FORCEPROP 1 LAST PATH I124
J 0
(4200 -2175);
DISPLAY 0.872340 (4200 -2175);
PAINT AQUA (4200 -2175);
DISPLAY INVISIBLE (4200 -2175);
FORCEADD Q_RES..2
(4125 -1950);
FORCEPROP 1 LAST LOCATION R4195
J 0
(4170 -1825);
DISPLAY 0.638298 (4170 -1825);
FORCEPROP 0 LAST $SEC 1
J 0
(4175 -1775);
DISPLAY 0.680851 (4175 -1775);
PAINT MONO (4175 -1775);
DISPLAY INVISIBLE (4175 -1775);
FORCEPROP 0 LAST CDS_SEC 1
J 0
(4175 -1775);
DISPLAY 1.021277 (4175 -1775);
DISPLAY INVISIBLE (4175 -1775);
FORCEPROP 1 LASTPIN (4125 -1850) $PN 1
J 0
(4130 -1888);
DISPLAY 0.787234 (4130 -1888);
PAINT MONO (4130 -1888);
FORCEPROP 1 LASTPIN (4125 -2050) $PN 2
J 0
(4130 -2040);
DISPLAY 0.787234 (4130 -2040);
PAINT MONO (4130 -2040);
FORCEPROP 1 LAST MATERIAL CHIP
J 0
(4165 -2025);
DISPLAY 0.638298 (4165 -2025);
FORCEPROP 1 LAST PACK_TYPE 0402LF
J 0
(4165 -2075);
DISPLAY 0.638298 (4165 -2075);
FORCEPROP 1 LAST VALUE 1K
J 0
(4170 -1875);
DISPLAY 0.638298 (4170 -1875);
FORCEPROP 1 LAST WATTAGE 1/16W
J 0
(4165 -1975);
DISPLAY 0.638298 (4165 -1975);
FORCEPROP 1 LAST TOLERANCE 1%
J 0
(4170 -1925);
DISPLAY 0.638298 (4170 -1925);
FORCEPROP 2 LAST CDS_LIB pure_quanta
J 0
(4125 -1950);
DISPLAY INVISIBLE (4125 -1950);
FORCEPROP 1 LAST PATH I125
J 0
(4175 -1775);
DISPLAY 0.978723 (4175 -1775);
PAINT WHITE (4175 -1775);
DISPLAY INVISIBLE (4175 -1775);
FORCEPROP 1 LAST PART_NUMBER CS21002FB06
J 0
(4165 -2125);
DISPLAY 0.638298 (4165 -2125);
DISPLAY INVISIBLE (4165 -2125);
FORCEADD UNIVERSAL_GND..1
(4375 -2175);
FORCEPROP 3 LASTPIN (4375 -2125) SIG_NAME GND\g
J 0
(4385 -2115);
DISPLAY 0.659574 (4385 -2115);
PAINT MONO (4385 -2115);
DISPLAY INVISIBLE (4385 -2115);
FORCEPROP 2 LAST CDS_LIB pure_quanta_power
J 0
(4375 -2175);
PAINT MONO (4375 -2175);
DISPLAY INVISIBLE (4375 -2175);
FORCEPROP 1 LAST HDL_POWER GND
J 1
(4400 -2250);
DISPLAY 0.872340 (4400 -2250);
PAINT GREEN (4400 -2250);
DISPLAY INVISIBLE (4400 -2250);
FORCEPROP 1 LAST PATH I126
J 0
(4450 -2175);
DISPLAY 0.872340 (4450 -2175);
PAINT AQUA (4450 -2175);
DISPLAY INVISIBLE (4450 -2175);
FORCEADD Q_RES..2
(4375 -1950);
FORCEPROP 1 LAST LOCATION R4203
J 0
(4420 -1825);
DISPLAY 0.638298 (4420 -1825);
FORCEPROP 0 LAST $SEC 1
J 0
(4425 -1775);
DISPLAY 0.680851 (4425 -1775);
PAINT MONO (4425 -1775);
DISPLAY INVISIBLE (4425 -1775);
FORCEPROP 0 LAST CDS_SEC 1
J 0
(4425 -1775);
DISPLAY 1.021277 (4425 -1775);
DISPLAY INVISIBLE (4425 -1775);
FORCEPROP 1 LASTPIN (4375 -1850) $PN 1
J 0
(4380 -1888);
DISPLAY 0.787234 (4380 -1888);
PAINT MONO (4380 -1888);
FORCEPROP 1 LASTPIN (4375 -2050) $PN 2
J 0
(4380 -2040);
DISPLAY 0.787234 (4380 -2040);
PAINT MONO (4380 -2040);
FORCEPROP 1 LAST MATERIAL CHIP
J 0
(4415 -2025);
DISPLAY 0.638298 (4415 -2025);
FORCEPROP 1 LAST PACK_TYPE 0402LF
J 0
(4415 -2075);
DISPLAY 0.638298 (4415 -2075);
FORCEPROP 1 LAST WATTAGE 1/16W
J 0
(4415 -1975);
DISPLAY 0.638298 (4415 -1975);
FORCEPROP 1 LAST VALUE 1K
J 0
(4420 -1875);
DISPLAY 0.638298 (4420 -1875);
FORCEPROP 1 LAST TOLERANCE 1%
J 0
(4420 -1925);
DISPLAY 0.638298 (4420 -1925);
FORCEPROP 2 LAST CDS_LIB pure_quanta
J 0
(4375 -1950);
DISPLAY INVISIBLE (4375 -1950);
FORCEPROP 1 LAST PATH I127
J 0
(4425 -1775);
DISPLAY 0.978723 (4425 -1775);
PAINT WHITE (4425 -1775);
DISPLAY INVISIBLE (4425 -1775);
FORCEPROP 1 LAST PART_NUMBER CS21002FB06
J 0
(4415 -2125);
DISPLAY 0.638298 (4415 -2125);
DISPLAY INVISIBLE (4415 -2125);
FORCEADD Q_RES..2
(4125 -1350);
FORCEPROP 1 LAST LOCATION R4194
J 0
(4170 -1225);
DISPLAY 0.638298 (4170 -1225);
FORCEPROP 0 LAST $SEC 1
J 0
(4175 -1175);
DISPLAY 0.680851 (4175 -1175);
PAINT MONO (4175 -1175);
DISPLAY INVISIBLE (4175 -1175);
FORCEPROP 0 LAST CDS_SEC 1
J 0
(4175 -1175);
DISPLAY 1.021277 (4175 -1175);
DISPLAY INVISIBLE (4175 -1175);
FORCEPROP 1 LASTPIN (4125 -1250) $PN 1
J 0
(4130 -1288);
DISPLAY 0.787234 (4130 -1288);
PAINT MONO (4130 -1288);
FORCEPROP 1 LASTPIN (4125 -1450) $PN 2
J 0
(4130 -1440);
DISPLAY 0.787234 (4130 -1440);
PAINT MONO (4130 -1440);
FORCEPROP 1 LAST TOLERANCE 1%
J 0
(4170 -1325);
DISPLAY 0.638298 (4170 -1325);
FORCEPROP 1 LAST WATTAGE 1/16W
J 0
(4165 -1375);
DISPLAY 0.638298 (4165 -1375);
FORCEPROP 1 LAST VALUE 1K
J 0
(4170 -1275);
DISPLAY 0.638298 (4170 -1275);
FORCEPROP 1 LAST MATERIAL EMPTY
J 0
(4165 -1425);
DISPLAY 0.638298 (4165 -1425);
PAINT RED (4165 -1425);
FORCEPROP 1 LAST PACK_TYPE 0402LF
J 0
(4165 -1475);
DISPLAY 0.638298 (4165 -1475);
FORCEPROP 2 LAST CDS_LIB pure_quanta
J 0
(4125 -1350);
DISPLAY INVISIBLE (4125 -1350);
FORCEPROP 1 LAST PATH I128
J 0
(4175 -1175);
DISPLAY 0.978723 (4175 -1175);
PAINT WHITE (4175 -1175);
DISPLAY INVISIBLE (4175 -1175);
FORCEPROP 1 LAST PART_NUMBER CS21002FB06
J 0
(4165 -1525);
DISPLAY 0.638298 (4165 -1525);
DISPLAY INVISIBLE (4165 -1525);
FORCEADD Q_RES..2
(4375 -1350);
FORCEPROP 1 LAST LOCATION R4202
J 0
(4420 -1225);
DISPLAY 0.638298 (4420 -1225);
FORCEPROP 0 LAST $SEC 1
J 0
(4425 -1175);
DISPLAY 0.680851 (4425 -1175);
PAINT MONO (4425 -1175);
DISPLAY INVISIBLE (4425 -1175);
FORCEPROP 0 LAST CDS_SEC 1
J 0
(4425 -1175);
DISPLAY 1.021277 (4425 -1175);
DISPLAY INVISIBLE (4425 -1175);
FORCEPROP 1 LASTPIN (4375 -1250) $PN 1
J 0
(4380 -1288);
DISPLAY 0.787234 (4380 -1288);
PAINT MONO (4380 -1288);
FORCEPROP 1 LASTPIN (4375 -1450) $PN 2
J 0
(4380 -1440);
DISPLAY 0.787234 (4380 -1440);
PAINT MONO (4380 -1440);
FORCEPROP 1 LAST WATTAGE 1/16W
J 0
(4415 -1375);
DISPLAY 0.638298 (4415 -1375);
FORCEPROP 1 LAST VALUE 1K
J 0
(4420 -1275);
DISPLAY 0.638298 (4420 -1275);
FORCEPROP 1 LAST PACK_TYPE 0402LF
J 0
(4415 -1475);
DISPLAY 0.638298 (4415 -1475);
FORCEPROP 1 LAST TOLERANCE 1%
J 0
(4420 -1325);
DISPLAY 0.638298 (4420 -1325);
FORCEPROP 1 LAST MATERIAL EMPTY
J 0
(4415 -1425);
DISPLAY 0.638298 (4415 -1425);
PAINT RED (4415 -1425);
FORCEPROP 2 LAST CDS_LIB pure_quanta
J 0
(4375 -1350);
DISPLAY INVISIBLE (4375 -1350);
FORCEPROP 1 LAST PATH I129
J 0
(4425 -1175);
DISPLAY 0.978723 (4425 -1175);
PAINT WHITE (4425 -1175);
DISPLAY INVISIBLE (4425 -1175);
FORCEPROP 1 LAST PART_NUMBER CS21002FB06
J 0
(4415 -1525);
DISPLAY 0.638298 (4415 -1525);
DISPLAY INVISIBLE (4415 -1525);
FORCEADD UNIVERSAL_POWER..1
(4375 -925);
FORCEPROP 3 LASTPIN (4375 -975) SIG_NAME P3V3_AUX\g
J 0
(4385 -965);
DISPLAY 0.659574 (4385 -965);
PAINT MONO (4385 -965);
DISPLAY INVISIBLE (4385 -965);
FORCEPROP 1 LAST HDL_POWER P3V3_AUX
J 1
(4375 -875);
DISPLAY 0.872340 (4375 -875);
PAINT GREEN (4375 -875);
FORCEPROP 2 LAST CDS_LIB pure_quanta_power
J 0
(4375 -925);
PAINT MONO (4375 -925);
DISPLAY INVISIBLE (4375 -925);
FORCEPROP 1 LAST PATH I130
J 0
(4425 -900);
DISPLAY 0.872340 (4425 -900);
PAINT AQUA (4425 -900);
DISPLAY INVISIBLE (4425 -900);
FORCEADD OFFPAGE..3
R 2
(-1025 -2975);
FORCEPROP 2 LAST $XR0 253 
J 0
(-1305 -2975);
DISPLAY 0.638298 (-1305 -2975);
PAINT MONO (-1305 -2975);
FORCEPROP 2 LAST CDS_LIB standard
J 0
(-1025 -2975);
DISPLAY INVISIBLE (-1025 -2975);
FORCEPROP 1 LAST OFFPAGE TRUE
J 2
(-1350 -3100);
DISPLAY 0.872340 (-1350 -3100);
DISPLAY INVISIBLE (-1350 -3100);
FORCEPROP 1 LAST COMMENT_BODY TRUE
J 2
(-975 -3075);
DISPLAY 0.872340 (-975 -3075);
PAINT GREEN (-975 -3075);
DISPLAY INVISIBLE (-975 -3075);
FORCEPROP 2 LAST PATH I132
J 0
(-1225 -2925);
DISPLAY 1.021277 (-1225 -2925);
DISPLAY INVISIBLE (-1225 -2925);
FORCEADD OFFPAGE..1
(-1025 -2825);
FORCEPROP 2 LAST $XR0 253 
J 0
(-1277 -2825);
DISPLAY 0.638298 (-1277 -2825);
PAINT MONO (-1277 -2825);
FORCEPROP 2 LAST CDS_LIB standard
J 0
(-1025 -2825);
DISPLAY INVISIBLE (-1025 -2825);
FORCEPROP 1 LAST OFFPAGE TRUE
J 0
(-700 -2950);
DISPLAY 0.872340 (-700 -2950);
PAINT GREEN (-700 -2950);
DISPLAY INVISIBLE (-700 -2950);
FORCEPROP 1 LAST COMMENT_BODY TRUE
J 0
(-900 -2925);
DISPLAY 0.872340 (-900 -2925);
PAINT GREEN (-900 -2925);
DISPLAY INVISIBLE (-900 -2925);
FORCEPROP 2 LAST PATH I133
J 0
(-1200 -2775);
DISPLAY 1.021277 (-1200 -2775);
DISPLAY INVISIBLE (-1200 -2775);
FORCEADD Q_RES..1
(225 -2975);
FORCEPROP 1 LAST LOCATION R3553
J 0
(25 -2975);
DISPLAY 0.638298 (25 -2975);
FORCEPROP 0 LAST $SEC 1
J 0
(575 -2925);
DISPLAY 0.680851 (575 -2925);
PAINT MONO (575 -2925);
DISPLAY INVISIBLE (575 -2925);
FORCEPROP 0 LAST CDS_SEC 1
J 0
(575 -2925);
DISPLAY 1.021277 (575 -2925);
DISPLAY INVISIBLE (575 -2925);
FORCEPROP 1 LASTPIN (125 -2975) $PN 1
J 0
(137 -2963);
DISPLAY 0.787234 (137 -2963);
PAINT MONO (137 -2963);
FORCEPROP 1 LASTPIN (325 -2975) $PN 2
J 0
(287 -2963);
DISPLAY 0.787234 (287 -2963);
PAINT MONO (287 -2963);
FORCEPROP 1 LAST TOLERANCE 1%
J 0
(475 -2975);
DISPLAY 0.638298 (475 -2975);
FORCEPROP 1 LAST WATTAGE 1/16W
J 2
(-125 -2975);
DISPLAY 0.638298 (-125 -2975);
FORCEPROP 1 LAST VALUE 33.2
J 2
(450 -2975);
DISPLAY 0.638298 (450 -2975);
FORCEPROP 1 LAST PACK_TYPE 0402LF
J 0
(575 -2975);
DISPLAY 0.638298 (575 -2975);
FORCEPROP 1 LAST MATERIAL CHIP
J 0
(-100 -2975);
DISPLAY 0.638298 (-100 -2975);
FORCEPROP 2 LAST CDS_LIB pure_quanta
J 0
(225 -2975);
DISPLAY INVISIBLE (225 -2975);
FORCEPROP 1 LAST PATH I134
J 0
(175 -2825);
DISPLAY 0.978723 (175 -2825);
PAINT WHITE (175 -2825);
DISPLAY INVISIBLE (175 -2825);
FORCEPROP 1 LAST PART_NUMBER CS03322FB03
J 0
(50 -2775);
DISPLAY 0.638298 (50 -2775);
DISPLAY INVISIBLE (50 -2775);
FORCEADD Q_RES..1
(225 -3125);
FORCEPROP 1 LAST LOCATION R4212
J 0
(25 -3125);
DISPLAY 0.638298 (25 -3125);
FORCEPROP 0 LAST $SEC 1
J 0
(525 -3075);
DISPLAY 0.680851 (525 -3075);
PAINT MONO (525 -3075);
DISPLAY INVISIBLE (525 -3075);
FORCEPROP 0 LAST CDS_SEC 1
J 0
(525 -3075);
DISPLAY 1.021277 (525 -3075);
DISPLAY INVISIBLE (525 -3075);
FORCEPROP 1 LASTPIN (125 -3125) $PN 1
J 0
(137 -3113);
DISPLAY 0.787234 (137 -3113);
PAINT MONO (137 -3113);
FORCEPROP 1 LASTPIN (325 -3125) $PN 2
J 0
(287 -3113);
DISPLAY 0.787234 (287 -3113);
PAINT MONO (287 -3113);
FORCEPROP 1 LAST VALUE 0
J 2
(375 -3125);
DISPLAY 0.574468 (375 -3125);
FORCEPROP 1 LAST PACK_TYPE 0402LF
J 0
(525 -3125);
DISPLAY 0.574468 (525 -3125);
FORCEPROP 1 LAST MATERIAL CHIP
J 0
(400 -3125);
DISPLAY 0.574468 (400 -3125);
FORCEPROP 1 LAST TOLERANCE 5%
J 0
(25 -3200);
DISPLAY 0.723404 (25 -3200);
PAINT SKYBLUE (25 -3200);
DISPLAY INVISIBLE (25 -3200);
FORCEPROP 1 LAST WATTAGE 1/16W
J 2
(300 -3200);
DISPLAY 0.723404 (300 -3200);
PAINT SKYBLUE (300 -3200);
DISPLAY INVISIBLE (300 -3200);
FORCEPROP 2 LAST CDS_LIB pure_quanta
J 0
(225 -3125);
DISPLAY INVISIBLE (225 -3125);
FORCEPROP 1 LAST PATH I135
J 0
(175 -2975);
DISPLAY 0.978723 (175 -2975);
PAINT WHITE (175 -2975);
DISPLAY INVISIBLE (175 -2975);
FORCEPROP 1 LAST PART_NUMBER CS00002JB13
J 0
(-50 -3250);
DISPLAY 0.723404 (-50 -3250);
PAINT WHITE (-50 -3250);
DISPLAY INVISIBLE (-50 -3250);
FORCEADD Q_RES..1
(225 -2825);
FORCEPROP 1 LAST LOCATION R3554
J 0
(25 -2825);
DISPLAY 0.638298 (25 -2825);
FORCEPROP 0 LAST $SEC 1
J 0
(575 -2775);
DISPLAY 0.680851 (575 -2775);
PAINT MONO (575 -2775);
DISPLAY INVISIBLE (575 -2775);
FORCEPROP 0 LAST CDS_SEC 1
J 0
(575 -2775);
DISPLAY 1.021277 (575 -2775);
DISPLAY INVISIBLE (575 -2775);
FORCEPROP 1 LASTPIN (125 -2825) $PN 1
J 0
(137 -2813);
DISPLAY 0.787234 (137 -2813);
PAINT MONO (137 -2813);
FORCEPROP 1 LASTPIN (325 -2825) $PN 2
J 0
(287 -2813);
DISPLAY 0.787234 (287 -2813);
PAINT MONO (287 -2813);
FORCEPROP 1 LAST WATTAGE 1/16W
J 2
(-125 -2825);
DISPLAY 0.638298 (-125 -2825);
FORCEPROP 1 LAST MATERIAL CHIP
J 0
(-100 -2825);
DISPLAY 0.638298 (-100 -2825);
FORCEPROP 1 LAST TOLERANCE 1%
J 0
(475 -2825);
DISPLAY 0.638298 (475 -2825);
FORCEPROP 1 LAST PACK_TYPE 0402LF
J 0
(575 -2825);
DISPLAY 0.638298 (575 -2825);
FORCEPROP 1 LAST VALUE 33.2
J 2
(450 -2825);
DISPLAY 0.638298 (450 -2825);
FORCEPROP 2 LAST CDS_LIB pure_quanta
J 0
(225 -2825);
DISPLAY INVISIBLE (225 -2825);
FORCEPROP 1 LAST PATH I136
J 0
(175 -2675);
DISPLAY 0.978723 (175 -2675);
PAINT WHITE (175 -2675);
DISPLAY INVISIBLE (175 -2675);
FORCEPROP 1 LAST PART_NUMBER CS03322FB03
J 0
(100 -2725);
DISPLAY 0.638298 (100 -2725);
DISPLAY INVISIBLE (100 -2725);
FORCEADD UNIVERSAL_GND..1
(1550 -3400);
FORCEPROP 3 LASTPIN (1550 -3350) SIG_NAME GND\g
J 0
(1560 -3340);
DISPLAY 0.659574 (1560 -3340);
PAINT MONO (1560 -3340);
DISPLAY INVISIBLE (1560 -3340);
FORCEPROP 2 LAST CDS_LIB pure_quanta_power
J 0
(1550 -3400);
DISPLAY INVISIBLE (1550 -3400);
FORCEPROP 1 LAST HDL_POWER GND
J 1
(1575 -3475);
DISPLAY 0.872340 (1575 -3475);
PAINT GREEN (1575 -3475);
DISPLAY INVISIBLE (1575 -3475);
FORCEPROP 1 LAST PATH I137
J 0
(1625 -3400);
DISPLAY 0.872340 (1625 -3400);
PAINT AQUA (1625 -3400);
DISPLAY INVISIBLE (1625 -3400);
FORCEADD UNIVERSAL_GND..1
(2475 -2700);
FORCEPROP 3 LASTPIN (2475 -2650) SIG_NAME GND\g
J 0
(2485 -2640);
DISPLAY 0.659574 (2485 -2640);
PAINT MONO (2485 -2640);
DISPLAY INVISIBLE (2485 -2640);
FORCEPROP 2 LAST CDS_LIB pure_quanta_power
J 0
(2475 -2700);
DISPLAY INVISIBLE (2475 -2700);
FORCEPROP 1 LAST HDL_POWER GND
J 1
(2500 -2775);
DISPLAY 0.872340 (2500 -2775);
PAINT GREEN (2500 -2775);
DISPLAY INVISIBLE (2500 -2775);
FORCEPROP 1 LAST PATH I138
J 0
(2550 -2700);
DISPLAY 0.872340 (2550 -2700);
PAINT AQUA (2550 -2700);
DISPLAY INVISIBLE (2550 -2700);
FORCEADD Q_CAP..1
R 2
(2475 -2475);
FORCEPROP 1 LAST LOCATION C31
J 2
(2425 -2375);
DISPLAY 0.978723 (2425 -2375);
FORCEPROP 0 LAST $SEC 1
J 0
(2425 -2325);
DISPLAY 0.680851 (2425 -2325);
PAINT MONO (2425 -2325);
DISPLAY INVISIBLE (2425 -2325);
FORCEPROP 0 LAST CDS_SEC 1
J 0
(2425 -2325);
DISPLAY 1.021277 (2425 -2325);
DISPLAY INVISIBLE (2425 -2325);
FORCEPROP 1 LASTPIN (2475 -2375) $PN 1
J 2
(2465 -2395);
DISPLAY 0.787234 (2465 -2395);
PAINT MONO (2465 -2395);
FORCEPROP 1 LASTPIN (2475 -2575) $PN 2
J 2
(2465 -2595);
DISPLAY 0.787234 (2465 -2595);
PAINT MONO (2465 -2595);
FORCEPROP 1 LAST VALUE 0.1UF
J 2
(2425 -2425);
DISPLAY 0.510638 (2425 -2425);
FORCEPROP 1 LAST TOLERANCE 10%
J 2
(2425 -2525);
DISPLAY 0.510638 (2425 -2525);
FORCEPROP 1 LAST PACK_TYPE 0402
J 2
(2425 -2675);
DISPLAY 0.510638 (2425 -2675);
FORCEPROP 1 LAST MATERIAL X7R
J 2
(2425 -2575);
DISPLAY 0.510638 (2425 -2575);
FORCEPROP 1 LAST VOLTAGE 25V
J 2
(2425 -2475);
DISPLAY 0.510638 (2425 -2475);
FORCEPROP 2 LAST CDS_LIB pure_quanta
J 0
(2475 -2475);
DISPLAY INVISIBLE (2475 -2475);
FORCEPROP 1 LAST PATH I139
J 2
(2425 -2325);
DISPLAY 0.978723 (2425 -2325);
PAINT WHITE (2425 -2325);
DISPLAY INVISIBLE (2425 -2325);
FORCEPROP 1 LAST PART_NUMBER CH4104K1B00
J 2
(2425 -2625);
DISPLAY 0.510638 (2425 -2625);
DISPLAY INVISIBLE (2425 -2625);
FORCEADD UNIVERSAL_GND..1
(3825 -3650);
FORCEPROP 3 LASTPIN (3825 -3600) SIG_NAME GND\g
J 0
(3835 -3590);
DISPLAY 0.659574 (3835 -3590);
PAINT MONO (3835 -3590);
DISPLAY INVISIBLE (3835 -3590);
FORCEPROP 2 LAST CDS_LIB pure_quanta_power
J 0
(3825 -3650);
PAINT MONO (3825 -3650);
DISPLAY INVISIBLE (3825 -3650);
FORCEPROP 1 LAST HDL_POWER GND
J 1
(3850 -3725);
DISPLAY 0.872340 (3850 -3725);
PAINT GREEN (3850 -3725);
DISPLAY INVISIBLE (3850 -3725);
FORCEPROP 1 LAST PATH I140
J 0
(3900 -3650);
DISPLAY 0.872340 (3900 -3650);
PAINT AQUA (3900 -3650);
DISPLAY INVISIBLE (3900 -3650);
FORCEADD Q_RES..2
(3825 -3425);
FORCEPROP 1 LAST LOCATION R4185
J 0
(3870 -3300);
DISPLAY 0.638298 (3870 -3300);
FORCEPROP 0 LAST $SEC 1
J 0
(3875 -3250);
DISPLAY 0.680851 (3875 -3250);
PAINT MONO (3875 -3250);
DISPLAY INVISIBLE (3875 -3250);
FORCEPROP 0 LAST CDS_SEC 1
J 0
(3875 -3250);
DISPLAY 1.021277 (3875 -3250);
DISPLAY INVISIBLE (3875 -3250);
FORCEPROP 1 LASTPIN (3825 -3325) $PN 1
J 0
(3830 -3363);
DISPLAY 0.787234 (3830 -3363);
PAINT MONO (3830 -3363);
FORCEPROP 1 LASTPIN (3825 -3525) $PN 2
J 0
(3830 -3515);
DISPLAY 0.787234 (3830 -3515);
PAINT MONO (3830 -3515);
FORCEPROP 1 LAST TOLERANCE 1%
J 0
(3870 -3400);
DISPLAY 0.638298 (3870 -3400);
FORCEPROP 1 LAST WATTAGE 1/16W
J 0
(3865 -3450);
DISPLAY 0.638298 (3865 -3450);
FORCEPROP 1 LAST VALUE 1K
J 0
(3870 -3350);
DISPLAY 0.638298 (3870 -3350);
FORCEPROP 1 LAST PACK_TYPE 0402LF
J 0
(3865 -3550);
DISPLAY 0.638298 (3865 -3550);
FORCEPROP 1 LAST MATERIAL CHIP
J 0
(3865 -3500);
DISPLAY 0.638298 (3865 -3500);
FORCEPROP 2 LAST CDS_LIB pure_quanta
J 0
(3825 -3425);
DISPLAY INVISIBLE (3825 -3425);
FORCEPROP 1 LAST PATH I141
J 0
(3875 -3250);
DISPLAY 0.978723 (3875 -3250);
PAINT WHITE (3875 -3250);
DISPLAY INVISIBLE (3875 -3250);
FORCEPROP 1 LAST PART_NUMBER CS21002FB06
J 0
(3865 -3600);
DISPLAY 0.638298 (3865 -3600);
DISPLAY INVISIBLE (3865 -3600);
FORCEADD Q_RES..2
(3825 -2825);
FORCEPROP 1 LAST LOCATION R4184
J 0
(3870 -2700);
DISPLAY 0.638298 (3870 -2700);
FORCEPROP 0 LAST $SEC 1
J 0
(3875 -2650);
DISPLAY 0.680851 (3875 -2650);
PAINT MONO (3875 -2650);
DISPLAY INVISIBLE (3875 -2650);
FORCEPROP 0 LAST CDS_SEC 1
J 0
(3875 -2650);
DISPLAY 1.021277 (3875 -2650);
DISPLAY INVISIBLE (3875 -2650);
FORCEPROP 1 LASTPIN (3825 -2725) $PN 1
J 0
(3830 -2763);
DISPLAY 0.787234 (3830 -2763);
PAINT MONO (3830 -2763);
FORCEPROP 1 LASTPIN (3825 -2925) $PN 2
J 0
(3830 -2915);
DISPLAY 0.787234 (3830 -2915);
PAINT MONO (3830 -2915);
FORCEPROP 1 LAST MATERIAL EMPTY
J 0
(3865 -2900);
DISPLAY 0.638298 (3865 -2900);
PAINT RED (3865 -2900);
FORCEPROP 1 LAST PACK_TYPE 0402LF
J 0
(3865 -2950);
DISPLAY 0.638298 (3865 -2950);
FORCEPROP 1 LAST TOLERANCE 1%
J 0
(3870 -2800);
DISPLAY 0.638298 (3870 -2800);
FORCEPROP 1 LAST VALUE 1K
J 0
(3870 -2750);
DISPLAY 0.638298 (3870 -2750);
FORCEPROP 1 LAST WATTAGE 1/16W
J 0
(3865 -2850);
DISPLAY 0.638298 (3865 -2850);
FORCEPROP 2 LAST CDS_LIB pure_quanta
J 0
(3825 -2825);
DISPLAY INVISIBLE (3825 -2825);
FORCEPROP 1 LAST PATH I142
J 0
(3875 -2650);
DISPLAY 0.978723 (3875 -2650);
PAINT WHITE (3875 -2650);
DISPLAY INVISIBLE (3875 -2650);
FORCEPROP 1 LAST PART_NUMBER CS21002FB06
J 0
(3865 -3000);
DISPLAY 0.638298 (3865 -3000);
DISPLAY INVISIBLE (3865 -3000);
FORCEADD UNIVERSAL_POWER..1
(2475 -2150);
FORCEPROP 3 LASTPIN (2475 -2200) SIG_NAME P3V3_AUX\g
J 0
(2485 -2190);
DISPLAY 0.659574 (2485 -2190);
PAINT MONO (2485 -2190);
DISPLAY INVISIBLE (2485 -2190);
FORCEPROP 1 LAST HDL_POWER P3V3_AUX
J 1
(2475 -2100);
DISPLAY 0.872340 (2475 -2100);
PAINT GREEN (2475 -2100);
FORCEPROP 2 LAST CDS_LIB pure_quanta_power
J 0
(2475 -2150);
DISPLAY INVISIBLE (2475 -2150);
FORCEPROP 1 LAST PATH I143
J 0
(2525 -2125);
DISPLAY 0.872340 (2525 -2125);
PAINT AQUA (2525 -2125);
DISPLAY INVISIBLE (2525 -2125);
FORCEADD UNIVERSAL_GND..1
(4075 -3650);
FORCEPROP 3 LASTPIN (4075 -3600) SIG_NAME GND\g
J 0
(4085 -3590);
DISPLAY 0.659574 (4085 -3590);
PAINT MONO (4085 -3590);
DISPLAY INVISIBLE (4085 -3590);
FORCEPROP 2 LAST CDS_LIB pure_quanta_power
J 0
(4075 -3650);
PAINT MONO (4075 -3650);
DISPLAY INVISIBLE (4075 -3650);
FORCEPROP 1 LAST HDL_POWER GND
J 1
(4100 -3725);
DISPLAY 0.872340 (4100 -3725);
PAINT GREEN (4100 -3725);
DISPLAY INVISIBLE (4100 -3725);
FORCEPROP 1 LAST PATH I144
J 0
(4150 -3650);
DISPLAY 0.872340 (4150 -3650);
PAINT AQUA (4150 -3650);
DISPLAY INVISIBLE (4150 -3650);
FORCEADD Q_RES..2
(4075 -3425);
FORCEPROP 1 LAST LOCATION R4193
J 0
(4120 -3300);
DISPLAY 0.638298 (4120 -3300);
FORCEPROP 0 LAST $SEC 1
J 0
(4125 -3250);
DISPLAY 0.680851 (4125 -3250);
PAINT MONO (4125 -3250);
DISPLAY INVISIBLE (4125 -3250);
FORCEPROP 0 LAST CDS_SEC 1
J 0
(4125 -3250);
DISPLAY 1.021277 (4125 -3250);
DISPLAY INVISIBLE (4125 -3250);
FORCEPROP 1 LASTPIN (4075 -3325) $PN 1
J 0
(4080 -3363);
DISPLAY 0.787234 (4080 -3363);
PAINT MONO (4080 -3363);
FORCEPROP 1 LASTPIN (4075 -3525) $PN 2
J 0
(4080 -3515);
DISPLAY 0.787234 (4080 -3515);
PAINT MONO (4080 -3515);
FORCEPROP 1 LAST TOLERANCE 1%
J 0
(4120 -3400);
DISPLAY 0.638298 (4120 -3400);
FORCEPROP 1 LAST WATTAGE 1/16W
J 0
(4115 -3450);
DISPLAY 0.638298 (4115 -3450);
FORCEPROP 1 LAST VALUE 1K
J 0
(4120 -3350);
DISPLAY 0.638298 (4120 -3350);
FORCEPROP 1 LAST PACK_TYPE 0402LF
J 0
(4115 -3550);
DISPLAY 0.638298 (4115 -3550);
FORCEPROP 1 LAST MATERIAL CHIP
J 0
(4115 -3500);
DISPLAY 0.638298 (4115 -3500);
FORCEPROP 2 LAST CDS_LIB pure_quanta
J 0
(4075 -3425);
DISPLAY INVISIBLE (4075 -3425);
FORCEPROP 1 LAST PATH I145
J 0
(4125 -3250);
DISPLAY 0.978723 (4125 -3250);
PAINT WHITE (4125 -3250);
DISPLAY INVISIBLE (4125 -3250);
FORCEPROP 1 LAST PART_NUMBER CS21002FB06
J 0
(4115 -3600);
DISPLAY 0.638298 (4115 -3600);
DISPLAY INVISIBLE (4115 -3600);
FORCEADD UNIVERSAL_GND..1
(4325 -3650);
FORCEPROP 3 LASTPIN (4325 -3600) SIG_NAME GND\g
J 0
(4335 -3590);
DISPLAY 0.659574 (4335 -3590);
PAINT MONO (4335 -3590);
DISPLAY INVISIBLE (4335 -3590);
FORCEPROP 2 LAST CDS_LIB pure_quanta_power
J 0
(4325 -3650);
PAINT MONO (4325 -3650);
DISPLAY INVISIBLE (4325 -3650);
FORCEPROP 1 LAST HDL_POWER GND
J 1
(4350 -3725);
DISPLAY 0.872340 (4350 -3725);
PAINT GREEN (4350 -3725);
DISPLAY INVISIBLE (4350 -3725);
FORCEPROP 1 LAST PATH I146
J 0
(4400 -3650);
DISPLAY 0.872340 (4400 -3650);
PAINT AQUA (4400 -3650);
DISPLAY INVISIBLE (4400 -3650);
FORCEADD Q_RES..2
(4325 -3425);
FORCEPROP 1 LAST LOCATION R4201
J 0
(4370 -3300);
DISPLAY 0.638298 (4370 -3300);
FORCEPROP 0 LAST $SEC 1
J 0
(4375 -3250);
DISPLAY 0.680851 (4375 -3250);
PAINT MONO (4375 -3250);
DISPLAY INVISIBLE (4375 -3250);
FORCEPROP 0 LAST CDS_SEC 1
J 0
(4375 -3250);
DISPLAY 1.021277 (4375 -3250);
DISPLAY INVISIBLE (4375 -3250);
FORCEPROP 1 LASTPIN (4325 -3325) $PN 1
J 0
(4330 -3363);
DISPLAY 0.787234 (4330 -3363);
PAINT MONO (4330 -3363);
FORCEPROP 1 LASTPIN (4325 -3525) $PN 2
J 0
(4330 -3515);
DISPLAY 0.787234 (4330 -3515);
PAINT MONO (4330 -3515);
FORCEPROP 1 LAST TOLERANCE 1%
J 0
(4370 -3400);
DISPLAY 0.638298 (4370 -3400);
FORCEPROP 1 LAST VALUE 1K
J 0
(4370 -3350);
DISPLAY 0.638298 (4370 -3350);
FORCEPROP 1 LAST WATTAGE 1/16W
J 0
(4365 -3450);
DISPLAY 0.638298 (4365 -3450);
FORCEPROP 1 LAST PACK_TYPE 0402LF
J 0
(4365 -3550);
DISPLAY 0.638298 (4365 -3550);
FORCEPROP 1 LAST MATERIAL CHIP
J 0
(4365 -3500);
DISPLAY 0.638298 (4365 -3500);
FORCEPROP 2 LAST CDS_LIB pure_quanta
J 0
(4325 -3425);
DISPLAY INVISIBLE (4325 -3425);
FORCEPROP 1 LAST PATH I147
J 0
(4375 -3250);
DISPLAY 0.978723 (4375 -3250);
PAINT WHITE (4375 -3250);
DISPLAY INVISIBLE (4375 -3250);
FORCEPROP 1 LAST PART_NUMBER CS21002FB06
J 0
(4365 -3600);
DISPLAY 0.638298 (4365 -3600);
DISPLAY INVISIBLE (4365 -3600);
FORCEADD Q_RES..2
(4075 -2825);
FORCEPROP 1 LAST LOCATION R4192
J 0
(4120 -2700);
DISPLAY 0.638298 (4120 -2700);
FORCEPROP 0 LAST $SEC 1
J 0
(4125 -2650);
DISPLAY 0.680851 (4125 -2650);
PAINT MONO (4125 -2650);
DISPLAY INVISIBLE (4125 -2650);
FORCEPROP 0 LAST CDS_SEC 1
J 0
(4125 -2650);
DISPLAY 1.021277 (4125 -2650);
DISPLAY INVISIBLE (4125 -2650);
FORCEPROP 1 LASTPIN (4075 -2725) $PN 1
J 0
(4080 -2763);
DISPLAY 0.787234 (4080 -2763);
PAINT MONO (4080 -2763);
FORCEPROP 1 LASTPIN (4075 -2925) $PN 2
J 0
(4080 -2915);
DISPLAY 0.787234 (4080 -2915);
PAINT MONO (4080 -2915);
FORCEPROP 1 LAST MATERIAL EMPTY
J 0
(4115 -2900);
DISPLAY 0.638298 (4115 -2900);
PAINT RED (4115 -2900);
FORCEPROP 1 LAST PACK_TYPE 0402LF
J 0
(4115 -2950);
DISPLAY 0.638298 (4115 -2950);
FORCEPROP 1 LAST VALUE 1K
J 0
(4120 -2750);
DISPLAY 0.638298 (4120 -2750);
FORCEPROP 1 LAST WATTAGE 1/16W
J 0
(4115 -2850);
DISPLAY 0.638298 (4115 -2850);
FORCEPROP 1 LAST TOLERANCE 1%
J 0
(4120 -2800);
DISPLAY 0.638298 (4120 -2800);
FORCEPROP 2 LAST CDS_LIB pure_quanta
J 0
(4075 -2825);
DISPLAY INVISIBLE (4075 -2825);
FORCEPROP 1 LAST PATH I148
J 0
(4125 -2650);
DISPLAY 0.978723 (4125 -2650);
PAINT WHITE (4125 -2650);
DISPLAY INVISIBLE (4125 -2650);
FORCEPROP 1 LAST PART_NUMBER CS21002FB06
J 0
(4115 -3000);
DISPLAY 0.638298 (4115 -3000);
DISPLAY INVISIBLE (4115 -3000);
FORCEADD Q_RES..2
(4325 -2825);
FORCEPROP 1 LAST LOCATION R4200
J 0
(4370 -2700);
DISPLAY 0.638298 (4370 -2700);
FORCEPROP 0 LAST $SEC 1
J 0
(4375 -2650);
DISPLAY 0.680851 (4375 -2650);
PAINT MONO (4375 -2650);
DISPLAY INVISIBLE (4375 -2650);
FORCEPROP 0 LAST CDS_SEC 1
J 0
(4375 -2650);
DISPLAY 1.021277 (4375 -2650);
DISPLAY INVISIBLE (4375 -2650);
FORCEPROP 1 LASTPIN (4325 -2725) $PN 1
J 0
(4330 -2763);
DISPLAY 0.787234 (4330 -2763);
PAINT MONO (4330 -2763);
FORCEPROP 1 LASTPIN (4325 -2925) $PN 2
J 0
(4330 -2915);
DISPLAY 0.787234 (4330 -2915);
PAINT MONO (4330 -2915);
FORCEPROP 1 LAST MATERIAL EMPTY
J 0
(4365 -2900);
DISPLAY 0.638298 (4365 -2900);
PAINT RED (4365 -2900);
FORCEPROP 1 LAST TOLERANCE 1%
J 0
(4370 -2800);
DISPLAY 0.638298 (4370 -2800);
FORCEPROP 1 LAST PACK_TYPE 0402LF
J 0
(4365 -2950);
DISPLAY 0.638298 (4365 -2950);
FORCEPROP 1 LAST VALUE 1K
J 0
(4370 -2750);
DISPLAY 0.638298 (4370 -2750);
FORCEPROP 1 LAST WATTAGE 1/16W
J 0
(4365 -2850);
DISPLAY 0.638298 (4365 -2850);
FORCEPROP 2 LAST CDS_LIB pure_quanta
J 0
(4325 -2825);
DISPLAY INVISIBLE (4325 -2825);
FORCEPROP 1 LAST PATH I149
J 0
(4375 -2650);
DISPLAY 0.978723 (4375 -2650);
PAINT WHITE (4375 -2650);
DISPLAY INVISIBLE (4375 -2650);
FORCEPROP 1 LAST PART_NUMBER CS21002FB06
J 0
(4365 -3000);
DISPLAY 0.638298 (4365 -3000);
DISPLAY INVISIBLE (4365 -3000);
FORCEADD UNIVERSAL_POWER..1
(2600 2275);
FORCEPROP 3 LASTPIN (2600 2225) SIG_NAME P3V3_AUX\g
J 0
(2610 2235);
DISPLAY 0.659574 (2610 2235);
PAINT MONO (2610 2235);
DISPLAY INVISIBLE (2610 2235);
FORCEPROP 1 LAST HDL_POWER P3V3_AUX
J 1
(2600 2325);
DISPLAY 0.872340 (2600 2325);
PAINT GREEN (2600 2325);
FORCEPROP 2 LAST CDS_LIB pure_quanta_power
J 0
(2600 2275);
DISPLAY INVISIBLE (2600 2275);
FORCEPROP 1 LAST PATH I15
J 0
(2650 2300);
DISPLAY 0.872340 (2650 2300);
PAINT AQUA (2650 2300);
DISPLAY INVISIBLE (2650 2300);
FORCEADD UNIVERSAL_POWER..1
(4325 -2400);
FORCEPROP 3 LASTPIN (4325 -2450) SIG_NAME P3V3_AUX\g
J 0
(4335 -2440);
DISPLAY 0.659574 (4335 -2440);
PAINT MONO (4335 -2440);
DISPLAY INVISIBLE (4335 -2440);
FORCEPROP 1 LAST HDL_POWER P3V3_AUX
J 1
(4325 -2350);
DISPLAY 0.872340 (4325 -2350);
PAINT GREEN (4325 -2350);
FORCEPROP 2 LAST CDS_LIB pure_quanta_power
J 0
(4325 -2400);
PAINT MONO (4325 -2400);
DISPLAY INVISIBLE (4325 -2400);
FORCEPROP 1 LAST PATH I150
J 0
(4375 -2375);
DISPLAY 0.872340 (4375 -2375);
PAINT AQUA (4375 -2375);
DISPLAY INVISIBLE (4375 -2375);
FORCEADD UNIVERSAL_POWER..1
(-200 2025);
FORCEPROP 3 LASTPIN (-200 1975) SIG_NAME P3V3_AUX\g
J 0
(-190 1985);
DISPLAY 0.659574 (-190 1985);
PAINT MONO (-190 1985);
DISPLAY INVISIBLE (-190 1985);
FORCEPROP 1 LAST HDL_POWER P3V3_AUX
J 1
(-200 2075);
DISPLAY 0.872340 (-200 2075);
PAINT GREEN (-200 2075);
FORCEPROP 2 LAST CDS_LIB pure_quanta_power
J 0
(-200 2025);
DISPLAY INVISIBLE (-200 2025);
FORCEPROP 1 LAST PATH I153
J 0
(-150 2050);
DISPLAY 0.872340 (-150 2050);
PAINT AQUA (-150 2050);
DISPLAY INVISIBLE (-150 2050);
FORCEADD UNIVERSAL_POWER..1
(-250 550);
FORCEPROP 3 LASTPIN (-250 500) SIG_NAME P3V3_AUX\g
J 0
(-240 510);
DISPLAY 0.659574 (-240 510);
PAINT MONO (-240 510);
DISPLAY INVISIBLE (-240 510);
FORCEPROP 1 LAST HDL_POWER P3V3_AUX
J 1
(-250 600);
DISPLAY 0.872340 (-250 600);
PAINT GREEN (-250 600);
FORCEPROP 2 LAST CDS_LIB pure_quanta_power
J 0
(-250 550);
DISPLAY INVISIBLE (-250 550);
FORCEPROP 1 LAST PATH I154
J 0
(-200 575);
DISPLAY 0.872340 (-200 575);
PAINT AQUA (-200 575);
DISPLAY INVISIBLE (-200 575);
FORCEADD UNIVERSAL_POWER..1
(-250 -925);
FORCEPROP 3 LASTPIN (-250 -975) SIG_NAME P3V3_AUX\g
J 0
(-240 -965);
DISPLAY 0.659574 (-240 -965);
PAINT MONO (-240 -965);
DISPLAY INVISIBLE (-240 -965);
FORCEPROP 1 LAST HDL_POWER P3V3_AUX
J 1
(-250 -875);
DISPLAY 0.872340 (-250 -875);
PAINT GREEN (-250 -875);
FORCEPROP 2 LAST CDS_LIB pure_quanta_power
J 0
(-250 -925);
DISPLAY INVISIBLE (-250 -925);
FORCEPROP 1 LAST PATH I156
J 0
(-200 -900);
DISPLAY 0.872340 (-200 -900);
PAINT AQUA (-200 -900);
DISPLAY INVISIBLE (-200 -900);
FORCEADD UNIVERSAL_POWER..1
(-350 -2350);
FORCEPROP 3 LASTPIN (-350 -2400) SIG_NAME P3V3_AUX\g
J 0
(-340 -2390);
DISPLAY 0.659574 (-340 -2390);
PAINT MONO (-340 -2390);
DISPLAY INVISIBLE (-340 -2390);
FORCEPROP 1 LAST HDL_POWER P3V3_AUX
J 1
(-350 -2300);
DISPLAY 0.872340 (-350 -2300);
PAINT GREEN (-350 -2300);
FORCEPROP 2 LAST CDS_LIB pure_quanta_power
J 0
(-350 -2350);
DISPLAY INVISIBLE (-350 -2350);
FORCEPROP 1 LAST PATH I159
J 0
(-300 -2325);
DISPLAY 0.872340 (-300 -2325);
PAINT AQUA (-300 -2325);
DISPLAY INVISIBLE (-300 -2325);
FORCEADD Q_CAP..1
R 2
(2600 1950);
FORCEPROP 1 LAST LOCATION C2010
J 2
(2550 2050);
DISPLAY 0.978723 (2550 2050);
FORCEPROP 0 LAST $SEC 1
J 0
(2550 2100);
DISPLAY 0.680851 (2550 2100);
PAINT MONO (2550 2100);
DISPLAY INVISIBLE (2550 2100);
FORCEPROP 0 LAST CDS_SEC 1
J 0
(2550 2100);
DISPLAY 1.021277 (2550 2100);
DISPLAY INVISIBLE (2550 2100);
FORCEPROP 1 LASTPIN (2600 2050) $PN 1
J 2
(2590 2030);
DISPLAY 0.787234 (2590 2030);
PAINT MONO (2590 2030);
FORCEPROP 1 LASTPIN (2600 1850) $PN 2
J 2
(2590 1830);
DISPLAY 0.787234 (2590 1830);
PAINT MONO (2590 1830);
FORCEPROP 1 LAST MATERIAL X7R
J 2
(2550 1850);
DISPLAY 0.510638 (2550 1850);
FORCEPROP 1 LAST TOLERANCE 10%
J 2
(2550 1900);
DISPLAY 0.510638 (2550 1900);
FORCEPROP 1 LAST VOLTAGE 25V
J 2
(2550 1950);
DISPLAY 0.510638 (2550 1950);
FORCEPROP 1 LAST PACK_TYPE 0402
J 2
(2550 1750);
DISPLAY 0.510638 (2550 1750);
FORCEPROP 1 LAST VALUE 0.1UF
J 2
(2550 2000);
DISPLAY 0.510638 (2550 2000);
FORCEPROP 2 LAST CDS_LIB pure_quanta
J 0
(2600 1950);
DISPLAY INVISIBLE (2600 1950);
FORCEPROP 1 LAST PATH I16
J 2
(2550 2100);
DISPLAY 0.978723 (2550 2100);
PAINT WHITE (2550 2100);
DISPLAY INVISIBLE (2550 2100);
FORCEPROP 1 LAST PART_NUMBER CH4104K1B00
J 2
(2550 1800);
DISPLAY 0.510638 (2550 1800);
DISPLAY INVISIBLE (2550 1800);
FORCEADD OFFPAGE..2
R 2
(-1050 -3125);
FORCEPROP 2 LAST $XR1 85 
J 0
(-1395 -3125);
DISPLAY 0.638298 (-1395 -3125);
PAINT MONO (-1395 -3125);
FORCEPROP 2 LAST $XR0 236 
J 0
(-1305 -3125);
DISPLAY 0.638298 (-1305 -3125);
PAINT MONO (-1305 -3125);
FORCEPROP 2 LAST CDS_LIB standard
J 2
(-1050 -3125);
DISPLAY INVISIBLE (-1050 -3125);
FORCEPROP 1 LAST OFFPAGE TRUE
J 2
(-1375 -3250);
DISPLAY 0.872340 (-1375 -3250);
PAINT AQUA (-1375 -3250);
DISPLAY INVISIBLE (-1375 -3250);
FORCEPROP 1 LAST COMMENT_BODY TRUE
J 2
(-1005 -3220);
DISPLAY 0.872340 (-1005 -3220);
PAINT GREEN (-1005 -3220);
DISPLAY INVISIBLE (-1005 -3220);
FORCEPROP 2 LAST PATH I160
J 2
(-1225 -3050);
DISPLAY 1.021277 (-1225 -3050);
DISPLAY INVISIBLE (-1225 -3050);
FORCEADD OFFPAGE..2
R 2
(-975 -1650);
FORCEPROP 2 LAST $XR1 85 
J 0
(-1320 -1650);
DISPLAY 0.638298 (-1320 -1650);
PAINT MONO (-1320 -1650);
FORCEPROP 2 LAST $XR0 236 
J 0
(-1230 -1650);
DISPLAY 0.638298 (-1230 -1650);
PAINT MONO (-1230 -1650);
FORCEPROP 2 LAST CDS_LIB standard
J 0
(-975 -1650);
DISPLAY INVISIBLE (-975 -1650);
FORCEPROP 1 LAST OFFPAGE TRUE
J 2
(-1300 -1775);
DISPLAY 0.872340 (-1300 -1775);
PAINT AQUA (-1300 -1775);
DISPLAY INVISIBLE (-1300 -1775);
FORCEPROP 1 LAST COMMENT_BODY TRUE
J 2
(-930 -1745);
DISPLAY 0.872340 (-930 -1745);
PAINT GREEN (-930 -1745);
DISPLAY INVISIBLE (-930 -1745);
FORCEPROP 2 LAST PATH I161
J 0
(-925 -1575);
DISPLAY 1.021277 (-925 -1575);
DISPLAY INVISIBLE (-925 -1575);
FORCEADD OFFPAGE..2
R 2
(-975 -175);
FORCEPROP 2 LAST $XR1 85 
J 0
(-1320 -175);
DISPLAY 0.638298 (-1320 -175);
PAINT MONO (-1320 -175);
FORCEPROP 2 LAST $XR0 236 
J 0
(-1230 -175);
DISPLAY 0.638298 (-1230 -175);
PAINT MONO (-1230 -175);
FORCEPROP 2 LAST CDS_LIB standard
J 0
(-975 -175);
DISPLAY INVISIBLE (-975 -175);
FORCEPROP 1 LAST OFFPAGE TRUE
J 2
(-1300 -300);
DISPLAY 0.872340 (-1300 -300);
PAINT AQUA (-1300 -300);
DISPLAY INVISIBLE (-1300 -300);
FORCEPROP 1 LAST COMMENT_BODY TRUE
J 2
(-930 -270);
DISPLAY 0.872340 (-930 -270);
PAINT GREEN (-930 -270);
DISPLAY INVISIBLE (-930 -270);
FORCEPROP 2 LAST PATH I162
J 0
(-925 -100);
DISPLAY 1.021277 (-925 -100);
DISPLAY INVISIBLE (-925 -100);
FORCEADD OFFPAGE..2
R 2
(-900 1300);
FORCEPROP 2 LAST $XR1 85 
J 0
(-1275 1300);
DISPLAY 0.638298 (-1275 1300);
PAINT MONO (-1275 1300);
FORCEPROP 2 LAST $XR0 236 
J 0
(-1185 1300);
DISPLAY 0.638298 (-1185 1300);
PAINT MONO (-1185 1300);
FORCEPROP 2 LAST CDS_LIB standard
J 0
(-900 1300);
DISPLAY INVISIBLE (-900 1300);
FORCEPROP 1 LAST OFFPAGE TRUE
J 2
(-1225 1175);
DISPLAY 0.872340 (-1225 1175);
PAINT AQUA (-1225 1175);
DISPLAY INVISIBLE (-1225 1175);
FORCEPROP 1 LAST COMMENT_BODY TRUE
J 2
(-855 1205);
DISPLAY 0.872340 (-855 1205);
PAINT GREEN (-855 1205);
DISPLAY INVISIBLE (-855 1205);
FORCEPROP 2 LAST PATH I163
J 0
(-850 1375);
DISPLAY 1.021277 (-850 1375);
DISPLAY INVISIBLE (-850 1375);
FORCEADD LM75BD..1
(2150 1375);
FORCEPROP 1 LAST LOCATION U270
J 0
(1931 1981);
DISPLAY 0.723404 (1931 1981);
PAINT GREEN (1931 1981);
FORCEPROP 0 LAST $SEC 1
J 0
(1950 2125);
DISPLAY 0.680851 (1950 2125);
PAINT MONO (1950 2125);
DISPLAY INVISIBLE (1950 2125);
FORCEPROP 0 LAST CDS_SEC 1
J 0
(1950 2125);
DISPLAY 1.021277 (1950 2125);
DISPLAY INVISIBLE (1950 2125);
FORCEPROP 0 LASTPIN (2525 1450) $PN 7
J 0
(2535 1460);
DISPLAY 0.680851 (2535 1460);
PAINT MONO (2535 1460);
FORCEPROP 0 LASTPIN (2525 1300) $PN 6
J 0
(2535 1310);
DISPLAY 0.680851 (2535 1310);
PAINT MONO (2535 1310);
FORCEPROP 0 LASTPIN (2525 1150) $PN 5
J 0
(2535 1160);
DISPLAY 0.680851 (2535 1160);
PAINT MONO (2535 1160);
FORCEPROP 0 LASTPIN (1775 1150) $PN 4
J 2
(1765 1160);
DISPLAY 0.680851 (1765 1160);
PAINT MONO (1765 1160);
FORCEPROP 0 LASTPIN (1775 1300) $PN 3
J 2
(1765 1310);
DISPLAY 0.680851 (1765 1310);
PAINT MONO (1765 1310);
FORCEPROP 0 LASTPIN (1775 1450) $PN 2
J 2
(1765 1460);
DISPLAY 0.680851 (1765 1460);
PAINT MONO (1765 1460);
FORCEPROP 0 LASTPIN (1775 1600) $PN 1
J 2
(1765 1610);
DISPLAY 0.680851 (1765 1610);
PAINT MONO (1765 1610);
FORCEPROP 0 LASTPIN (2525 1600) $PN 8
J 0
(2535 1610);
DISPLAY 0.680851 (2535 1610);
PAINT MONO (2535 1610);
FORCEPROP 2 LAST PART_TYPE SMLF
J 0
(1950 2075);
DISPLAY 1.021277 (1950 2075);
FORCEPROP 2 LAST VALUE LM75BD
J 0
(1950 2025);
DISPLAY 1.021277 (1950 2025);
FORCEPROP 1 LAST MATERIAL IC
J 0
(1931 1707);
DISPLAY 0.723404 (1931 1707);
PAINT GREEN (1931 1707);
FORCEPROP 2 LAST CDS_LIB pure_quanta
J 0
(2150 1375);
DISPLAY INVISIBLE (2150 1375);
FORCEPROP 1 LAST CDS_LMAN_SYM_OUTLINE -225,325,225,-325
J 0
(2150 1375);
DISPLAY 0.468085 (2150 1375);
PAINT GREEN (2150 1375);
DISPLAY INVISIBLE (2150 1375);
FORCEPROP 1 LAST NEEDS_NO_SIZE TRUE
J 0
(2150 1375);
DISPLAY 0.723404 (2150 1375);
PAINT GREEN (2150 1375);
DISPLAY INVISIBLE (2150 1375);
FORCEPROP 1 LAST PATH I164
J 0
(2150 1375);
DISPLAY 0.723404 (2150 1375);
PAINT GREEN (2150 1375);
DISPLAY INVISIBLE (2150 1375);
FORCEPROP 1 LAST PART_NUMBER AL0075BD000
J 0
(1931 1834);
DISPLAY 0.723404 (1931 1834);
PAINT GREEN (1931 1834);
DISPLAY INVISIBLE (1931 1834);
FORCEADD LM75BD..1
(2100 -100);
FORCEPROP 1 LAST LOCATION U271
J 0
(1881 506);
DISPLAY 0.723404 (1881 506);
PAINT GREEN (1881 506);
FORCEPROP 0 LAST $SEC 1
J 0
(1900 650);
DISPLAY 0.680851 (1900 650);
PAINT MONO (1900 650);
DISPLAY INVISIBLE (1900 650);
FORCEPROP 0 LAST CDS_SEC 1
J 0
(1900 650);
DISPLAY 1.021277 (1900 650);
DISPLAY INVISIBLE (1900 650);
FORCEPROP 0 LASTPIN (2475 -25) $PN 7
J 0
(2485 -15);
DISPLAY 0.680851 (2485 -15);
PAINT MONO (2485 -15);
FORCEPROP 0 LASTPIN (2475 -175) $PN 6
J 0
(2485 -165);
DISPLAY 0.680851 (2485 -165);
PAINT MONO (2485 -165);
FORCEPROP 0 LASTPIN (2475 -325) $PN 5
J 0
(2485 -315);
DISPLAY 0.680851 (2485 -315);
PAINT MONO (2485 -315);
FORCEPROP 0 LASTPIN (1725 -325) $PN 4
J 2
(1715 -315);
DISPLAY 0.680851 (1715 -315);
PAINT MONO (1715 -315);
FORCEPROP 0 LASTPIN (1725 -175) $PN 3
J 2
(1715 -165);
DISPLAY 0.680851 (1715 -165);
PAINT MONO (1715 -165);
FORCEPROP 0 LASTPIN (1725 -25) $PN 2
J 2
(1715 -15);
DISPLAY 0.680851 (1715 -15);
PAINT MONO (1715 -15);
FORCEPROP 0 LASTPIN (1725 125) $PN 1
J 2
(1715 135);
DISPLAY 0.680851 (1715 135);
PAINT MONO (1715 135);
FORCEPROP 0 LASTPIN (2475 125) $PN 8
J 0
(2485 135);
DISPLAY 0.680851 (2485 135);
PAINT MONO (2485 135);
FORCEPROP 1 LAST MATERIAL IC
J 0
(1881 232);
DISPLAY 0.723404 (1881 232);
PAINT GREEN (1881 232);
FORCEPROP 2 LAST PART_TYPE SMLF
J 0
(1900 600);
DISPLAY 1.021277 (1900 600);
FORCEPROP 2 LAST VALUE LM75BD
J 0
(1900 550);
DISPLAY 1.021277 (1900 550);
FORCEPROP 1 LAST CDS_LMAN_SYM_OUTLINE -225,325,225,-325
J 0
(2100 -100);
DISPLAY 0.468085 (2100 -100);
PAINT GREEN (2100 -100);
DISPLAY INVISIBLE (2100 -100);
FORCEPROP 2 LAST CDS_LIB pure_quanta
J 0
(2100 -100);
DISPLAY INVISIBLE (2100 -100);
FORCEPROP 1 LAST NEEDS_NO_SIZE TRUE
J 0
(2100 -100);
DISPLAY 0.723404 (2100 -100);
PAINT GREEN (2100 -100);
DISPLAY INVISIBLE (2100 -100);
FORCEPROP 1 LAST PATH I165
J 0
(2100 -100);
DISPLAY 0.723404 (2100 -100);
PAINT GREEN (2100 -100);
DISPLAY INVISIBLE (2100 -100);
FORCEPROP 1 LAST PART_NUMBER AL0075BD000
J 0
(1881 359);
DISPLAY 0.723404 (1881 359);
PAINT GREEN (1881 359);
DISPLAY INVISIBLE (1881 359);
FORCEADD LM75BD..1
(2075 -1575);
FORCEPROP 1 LAST LOCATION U272
J 0
(1856 -969);
DISPLAY 0.723404 (1856 -969);
PAINT GREEN (1856 -969);
FORCEPROP 0 LAST $SEC 1
J 0
(1875 -825);
DISPLAY 0.680851 (1875 -825);
PAINT MONO (1875 -825);
DISPLAY INVISIBLE (1875 -825);
FORCEPROP 0 LAST CDS_SEC 1
J 0
(1875 -825);
DISPLAY 1.021277 (1875 -825);
DISPLAY INVISIBLE (1875 -825);
FORCEPROP 0 LASTPIN (2450 -1500) $PN 7
J 0
(2460 -1490);
DISPLAY 0.680851 (2460 -1490);
PAINT MONO (2460 -1490);
FORCEPROP 0 LASTPIN (2450 -1650) $PN 6
J 0
(2460 -1640);
DISPLAY 0.680851 (2460 -1640);
PAINT MONO (2460 -1640);
FORCEPROP 0 LASTPIN (2450 -1800) $PN 5
J 0
(2460 -1790);
DISPLAY 0.680851 (2460 -1790);
PAINT MONO (2460 -1790);
FORCEPROP 0 LASTPIN (1700 -1800) $PN 4
J 2
(1690 -1790);
DISPLAY 0.680851 (1690 -1790);
PAINT MONO (1690 -1790);
FORCEPROP 0 LASTPIN (1700 -1650) $PN 3
J 2
(1690 -1640);
DISPLAY 0.680851 (1690 -1640);
PAINT MONO (1690 -1640);
FORCEPROP 0 LASTPIN (1700 -1500) $PN 2
J 2
(1690 -1490);
DISPLAY 0.680851 (1690 -1490);
PAINT MONO (1690 -1490);
FORCEPROP 0 LASTPIN (1700 -1350) $PN 1
J 2
(1690 -1340);
DISPLAY 0.680851 (1690 -1340);
PAINT MONO (1690 -1340);
FORCEPROP 0 LASTPIN (2450 -1350) $PN 8
J 0
(2460 -1340);
DISPLAY 0.680851 (2460 -1340);
PAINT MONO (2460 -1340);
FORCEPROP 2 LAST VALUE LM75BD
J 0
(1875 -925);
DISPLAY 1.021277 (1875 -925);
FORCEPROP 1 LAST MATERIAL IC
J 0
(1856 -1243);
DISPLAY 0.723404 (1856 -1243);
PAINT GREEN (1856 -1243);
FORCEPROP 2 LAST PART_TYPE SMLF
J 0
(1875 -875);
DISPLAY 1.021277 (1875 -875);
FORCEPROP 2 LAST CDS_LIB pure_quanta
J 0
(2075 -1575);
DISPLAY INVISIBLE (2075 -1575);
FORCEPROP 1 LAST CDS_LMAN_SYM_OUTLINE -225,325,225,-325
J 0
(2075 -1575);
DISPLAY 0.468085 (2075 -1575);
PAINT GREEN (2075 -1575);
DISPLAY INVISIBLE (2075 -1575);
FORCEPROP 1 LAST NEEDS_NO_SIZE TRUE
J 0
(2075 -1575);
DISPLAY 0.723404 (2075 -1575);
PAINT GREEN (2075 -1575);
DISPLAY INVISIBLE (2075 -1575);
FORCEPROP 1 LAST PATH I166
J 0
(2075 -1575);
DISPLAY 0.723404 (2075 -1575);
PAINT GREEN (2075 -1575);
DISPLAY INVISIBLE (2075 -1575);
FORCEPROP 1 LAST PART_NUMBER AL0075BD000
J 0
(1856 -1116);
DISPLAY 0.723404 (1856 -1116);
PAINT GREEN (1856 -1116);
DISPLAY INVISIBLE (1856 -1116);
FORCEADD LM75BD..1
(2025 -3050);
FORCEPROP 1 LAST LOCATION U273
J 0
(1806 -2444);
DISPLAY 0.723404 (1806 -2444);
PAINT GREEN (1806 -2444);
FORCEPROP 0 LAST $SEC 1
J 0
(1825 -2300);
DISPLAY 0.680851 (1825 -2300);
PAINT MONO (1825 -2300);
DISPLAY INVISIBLE (1825 -2300);
FORCEPROP 0 LAST CDS_SEC 1
J 0
(1825 -2300);
DISPLAY 1.021277 (1825 -2300);
DISPLAY INVISIBLE (1825 -2300);
FORCEPROP 0 LASTPIN (2400 -2975) $PN 7
J 0
(2410 -2965);
DISPLAY 0.680851 (2410 -2965);
PAINT MONO (2410 -2965);
FORCEPROP 0 LASTPIN (2400 -3125) $PN 6
J 0
(2410 -3115);
DISPLAY 0.680851 (2410 -3115);
PAINT MONO (2410 -3115);
FORCEPROP 0 LASTPIN (2400 -3275) $PN 5
J 0
(2410 -3265);
DISPLAY 0.680851 (2410 -3265);
PAINT MONO (2410 -3265);
FORCEPROP 0 LASTPIN (1650 -3275) $PN 4
J 2
(1640 -3265);
DISPLAY 0.680851 (1640 -3265);
PAINT MONO (1640 -3265);
FORCEPROP 0 LASTPIN (1650 -3125) $PN 3
J 2
(1640 -3115);
DISPLAY 0.680851 (1640 -3115);
PAINT MONO (1640 -3115);
FORCEPROP 0 LASTPIN (1650 -2975) $PN 2
J 2
(1640 -2965);
DISPLAY 0.680851 (1640 -2965);
PAINT MONO (1640 -2965);
FORCEPROP 0 LASTPIN (1650 -2825) $PN 1
J 2
(1640 -2815);
DISPLAY 0.680851 (1640 -2815);
PAINT MONO (1640 -2815);
FORCEPROP 0 LASTPIN (2400 -2825) $PN 8
J 0
(2410 -2815);
DISPLAY 0.680851 (2410 -2815);
PAINT MONO (2410 -2815);
FORCEPROP 2 LAST VALUE LM75BD
J 0
(1825 -2400);
DISPLAY 1.021277 (1825 -2400);
FORCEPROP 2 LAST PART_TYPE SMLF
J 0
(1825 -2350);
DISPLAY 1.021277 (1825 -2350);
FORCEPROP 1 LAST MATERIAL IC
J 0
(1806 -2718);
DISPLAY 0.723404 (1806 -2718);
PAINT GREEN (1806 -2718);
FORCEPROP 1 LAST NEEDS_NO_SIZE TRUE
J 0
(2025 -3050);
DISPLAY 0.723404 (2025 -3050);
PAINT GREEN (2025 -3050);
DISPLAY INVISIBLE (2025 -3050);
FORCEPROP 1 LAST CDS_LMAN_SYM_OUTLINE -225,325,225,-325
J 0
(2025 -3050);
DISPLAY 0.468085 (2025 -3050);
PAINT GREEN (2025 -3050);
DISPLAY INVISIBLE (2025 -3050);
FORCEPROP 2 LAST CDS_LIB pure_quanta
J 0
(2025 -3050);
DISPLAY INVISIBLE (2025 -3050);
FORCEPROP 1 LAST PATH I167
J 0
(2025 -3050);
DISPLAY 0.723404 (2025 -3050);
PAINT GREEN (2025 -3050);
DISPLAY INVISIBLE (2025 -3050);
FORCEPROP 1 LAST PART_NUMBER AL0075BD000
J 0
(1806 -2591);
DISPLAY 0.723404 (1806 -2591);
PAINT GREEN (1806 -2591);
DISPLAY INVISIBLE (1806 -2591);
FORCEADD Q_RES..2
(-200 1800);
FORCEPROP 1 LAST LOCATION R4211
J 0
(-150 1950);
DISPLAY 0.638298 (-150 1950);
FORCEPROP 0 LAST $SEC 1
J 0
(-150 2000);
DISPLAY 0.680851 (-150 2000);
PAINT MONO (-150 2000);
DISPLAY INVISIBLE (-150 2000);
FORCEPROP 0 LAST CDS_SEC 1
J 0
(-150 2000);
DISPLAY 1.021277 (-150 2000);
DISPLAY INVISIBLE (-150 2000);
FORCEPROP 1 LASTPIN (-200 1900) $PN 1
J 0
(-195 1862);
DISPLAY 0.787234 (-195 1862);
PAINT MONO (-195 1862);
FORCEPROP 1 LASTPIN (-200 1700) $PN 2
J 0
(-195 1710);
DISPLAY 0.787234 (-195 1710);
PAINT MONO (-195 1710);
FORCEPROP 1 LAST VALUE 200K
J 0
(-150 1900);
DISPLAY 0.510638 (-150 1900);
FORCEPROP 1 LAST PACK_TYPE 0402LF
J 0
(-150 1650);
DISPLAY 0.510638 (-150 1650);
FORCEPROP 1 LAST MATERIAL CHIP
J 0
(-150 1750);
DISPLAY 0.510638 (-150 1750);
FORCEPROP 1 LAST WATTAGE 1/16W
J 0
(-150 1800);
DISPLAY 0.510638 (-150 1800);
FORCEPROP 1 LAST TOLERANCE 1%
J 0
(-150 1850);
DISPLAY 0.510638 (-150 1850);
FORCEPROP 2 LAST CDS_LIB pure_quanta
J 0
(-200 1800);
DISPLAY INVISIBLE (-200 1800);
FORCEPROP 1 LAST PATH I168
J 0
(-150 1975);
DISPLAY 0.978723 (-150 1975);
PAINT WHITE (-150 1975);
DISPLAY INVISIBLE (-150 1975);
FORCEPROP 1 LAST PART_NUMBER CS42002FB05
J 0
(-150 1700);
DISPLAY 0.510638 (-150 1700);
DISPLAY INVISIBLE (-150 1700);
FORCEADD Q_RES..2
(-250 325);
FORCEPROP 1 LAST LOCATION R4209
J 0
(-200 475);
DISPLAY 0.404255 (-200 475);
FORCEPROP 0 LAST $SEC 1
J 0
(-200 500);
DISPLAY 0.680851 (-200 500);
PAINT MONO (-200 500);
DISPLAY INVISIBLE (-200 500);
FORCEPROP 0 LAST CDS_SEC 1
J 0
(-200 500);
DISPLAY 1.021277 (-200 500);
DISPLAY INVISIBLE (-200 500);
FORCEPROP 1 LASTPIN (-250 425) $PN 1
J 0
(-245 387);
DISPLAY 0.787234 (-245 387);
PAINT MONO (-245 387);
FORCEPROP 1 LASTPIN (-250 225) $PN 2
J 0
(-245 235);
DISPLAY 0.787234 (-245 235);
PAINT MONO (-245 235);
FORCEPROP 1 LAST MATERIAL EMPTY
J 0
(-200 300);
DISPLAY 0.319149 (-200 300);
PAINT RED (-200 300);
FORCEPROP 1 LAST WATTAGE 1/16W
J 0
(-200 350);
DISPLAY 0.319149 (-200 350);
FORCEPROP 1 LAST PACK_TYPE 0402LF
J 0
(-200 200);
DISPLAY 0.319149 (-200 200);
FORCEPROP 1 LAST TOLERANCE 1%
J 0
(-200 375);
DISPLAY 0.510638 (-200 375);
FORCEPROP 1 LAST VALUE 200K
J 0
(-200 450);
DISPLAY 0.319149 (-200 450);
FORCEPROP 2 LAST CDS_LIB pure_quanta
J 0
(-250 325);
DISPLAY INVISIBLE (-250 325);
FORCEPROP 1 LAST PATH I169
J 0
(-200 500);
DISPLAY 0.978723 (-200 500);
PAINT WHITE (-200 500);
DISPLAY INVISIBLE (-200 500);
FORCEPROP 1 LAST PART_NUMBER CS42002FB05
J 0
(-200 250);
DISPLAY 0.319149 (-200 250);
DISPLAY INVISIBLE (-200 250);
FORCEADD UNIVERSAL_GND..1
(2600 1725);
FORCEPROP 3 LASTPIN (2600 1775) SIG_NAME GND\g
J 0
(2610 1785);
DISPLAY 0.659574 (2610 1785);
PAINT MONO (2610 1785);
DISPLAY INVISIBLE (2610 1785);
FORCEPROP 2 LAST CDS_LIB pure_quanta_power
J 0
(2600 1725);
DISPLAY INVISIBLE (2600 1725);
FORCEPROP 1 LAST HDL_POWER GND
J 1
(2625 1650);
DISPLAY 0.872340 (2625 1650);
PAINT GREEN (2625 1650);
DISPLAY INVISIBLE (2625 1650);
FORCEPROP 1 LAST PATH I17
J 0
(2675 1725);
DISPLAY 0.872340 (2675 1725);
PAINT AQUA (2675 1725);
DISPLAY INVISIBLE (2675 1725);
FORCEADD Q_RES..2
(-250 -1175);
FORCEPROP 1 LAST LOCATION R4210
J 0
(-200 -1050);
DISPLAY 0.510638 (-200 -1050);
FORCEPROP 0 LAST $SEC 1
J 0
(-200 -1025);
DISPLAY 0.680851 (-200 -1025);
PAINT MONO (-200 -1025);
DISPLAY INVISIBLE (-200 -1025);
FORCEPROP 0 LAST CDS_SEC 1
J 0
(-200 -1025);
DISPLAY 1.021277 (-200 -1025);
DISPLAY INVISIBLE (-200 -1025);
FORCEPROP 1 LASTPIN (-250 -1075) $PN 1
J 0
(-245 -1113);
DISPLAY 0.787234 (-245 -1113);
PAINT MONO (-245 -1113);
FORCEPROP 1 LASTPIN (-250 -1275) $PN 2
J 0
(-245 -1265);
DISPLAY 0.787234 (-245 -1265);
PAINT MONO (-245 -1265);
FORCEPROP 1 LAST VALUE 200K
J 0
(-200 -1075);
DISPLAY 0.319149 (-200 -1075);
FORCEPROP 1 LAST TOLERANCE 1%
J 0
(-200 -1125);
DISPLAY 0.510638 (-200 -1125);
FORCEPROP 1 LAST PACK_TYPE 0402LF
J 0
(-200 -1300);
DISPLAY 0.319149 (-200 -1300);
FORCEPROP 1 LAST WATTAGE 1/16W
J 0
(-200 -1150);
DISPLAY 0.319149 (-200 -1150);
FORCEPROP 1 LAST MATERIAL EMPTY
J 0
(-200 -1200);
DISPLAY 0.319149 (-200 -1200);
PAINT RED (-200 -1200);
FORCEPROP 2 LAST CDS_LIB pure_quanta
J 0
(-250 -1175);
DISPLAY INVISIBLE (-250 -1175);
FORCEPROP 1 LAST PATH I170
J 0
(-200 -1000);
DISPLAY 0.978723 (-200 -1000);
PAINT WHITE (-200 -1000);
DISPLAY INVISIBLE (-200 -1000);
FORCEPROP 1 LAST PART_NUMBER CS42002FB05
J 0
(-200 -1250);
DISPLAY 0.319149 (-200 -1250);
DISPLAY INVISIBLE (-200 -1250);
FORCEADD Q_RES..2
(-350 -2625);
FORCEPROP 1 LAST LOCATION R4208
J 0
(-300 -2500);
DISPLAY 0.510638 (-300 -2500);
FORCEPROP 0 LAST $SEC 1
J 0
(-300 -2475);
DISPLAY 0.680851 (-300 -2475);
PAINT MONO (-300 -2475);
DISPLAY INVISIBLE (-300 -2475);
FORCEPROP 0 LAST CDS_SEC 1
J 0
(-300 -2475);
DISPLAY 1.021277 (-300 -2475);
DISPLAY INVISIBLE (-300 -2475);
FORCEPROP 1 LASTPIN (-350 -2525) $PN 1
J 0
(-345 -2563);
DISPLAY 0.787234 (-345 -2563);
PAINT MONO (-345 -2563);
FORCEPROP 1 LASTPIN (-350 -2725) $PN 2
J 0
(-345 -2715);
DISPLAY 0.787234 (-345 -2715);
PAINT MONO (-345 -2715);
FORCEPROP 1 LAST PACK_TYPE 0402LF
J 0
(-300 -2750);
DISPLAY 0.319149 (-300 -2750);
FORCEPROP 1 LAST MATERIAL EMPTY
J 0
(-300 -2650);
DISPLAY 0.319149 (-300 -2650);
PAINT RED (-300 -2650);
FORCEPROP 1 LAST WATTAGE 1/16W
J 0
(-300 -2600);
DISPLAY 0.319149 (-300 -2600);
FORCEPROP 1 LAST TOLERANCE 1%
J 0
(-300 -2575);
DISPLAY 0.510638 (-300 -2575);
FORCEPROP 1 LAST VALUE 200K
J 0
(-300 -2525);
DISPLAY 0.319149 (-300 -2525);
FORCEPROP 2 LAST CDS_LIB pure_quanta
J 0
(-350 -2625);
DISPLAY INVISIBLE (-350 -2625);
FORCEPROP 1 LAST PATH I171
J 0
(-300 -2450);
DISPLAY 0.978723 (-300 -2450);
PAINT WHITE (-300 -2450);
DISPLAY INVISIBLE (-300 -2450);
FORCEPROP 1 LAST PART_NUMBER CS42002FB05
J 0
(-300 -2700);
DISPLAY 0.319149 (-300 -2700);
DISPLAY INVISIBLE (-300 -2700);
FORCEADD UNIVERSAL_GND..1
(1675 1025);
FORCEPROP 3 LASTPIN (1675 1075) SIG_NAME GND\g
J 0
(1685 1085);
DISPLAY 0.659574 (1685 1085);
PAINT MONO (1685 1085);
DISPLAY INVISIBLE (1685 1085);
FORCEPROP 2 LAST CDS_LIB pure_quanta_power
J 0
(1675 1025);
DISPLAY INVISIBLE (1675 1025);
FORCEPROP 1 LAST HDL_POWER GND
J 1
(1700 950);
DISPLAY 0.872340 (1700 950);
PAINT GREEN (1700 950);
DISPLAY INVISIBLE (1700 950);
FORCEPROP 1 LAST PATH I21
J 0
(1750 1025);
DISPLAY 0.872340 (1750 1025);
PAINT AQUA (1750 1025);
DISPLAY INVISIBLE (1750 1025);
FORCEADD OFFPAGE..1
(-900 1600);
FORCEPROP 2 LAST $XR1 272 
J 0
(-1272 1600);
DISPLAY 0.638298 (-1272 1600);
PAINT MONO (-1272 1600);
FORCEPROP 2 LAST $XR0 253 
J 0
(-1152 1600);
DISPLAY 0.638298 (-1152 1600);
PAINT MONO (-1152 1600);
FORCEPROP 2 LAST CDS_LIB standard
J 0
(-900 1600);
DISPLAY INVISIBLE (-900 1600);
FORCEPROP 1 LAST OFFPAGE TRUE
J 0
(-575 1475);
DISPLAY 0.872340 (-575 1475);
PAINT GREEN (-575 1475);
DISPLAY INVISIBLE (-575 1475);
FORCEPROP 1 LAST COMMENT_BODY TRUE
J 0
(-775 1500);
DISPLAY 0.872340 (-775 1500);
PAINT GREEN (-775 1500);
DISPLAY INVISIBLE (-775 1500);
FORCEPROP 2 LAST PATH I75
J 2
(-1100 1650);
DISPLAY 1.021277 (-1100 1650);
DISPLAY INVISIBLE (-1100 1650);
FORCEADD OFFPAGE..3
R 2
(-900 1450);
FORCEPROP 2 LAST $XR1 272 
J 0
(-1300 1450);
DISPLAY 0.638298 (-1300 1450);
PAINT MONO (-1300 1450);
FORCEPROP 2 LAST $XR0 253 
J 0
(-1180 1450);
DISPLAY 0.638298 (-1180 1450);
PAINT MONO (-1180 1450);
FORCEPROP 2 LAST CDS_LIB standard
J 0
(-900 1450);
DISPLAY INVISIBLE (-900 1450);
FORCEPROP 1 LAST OFFPAGE TRUE
J 2
(-1225 1325);
DISPLAY 0.872340 (-1225 1325);
DISPLAY INVISIBLE (-1225 1325);
FORCEPROP 1 LAST COMMENT_BODY TRUE
J 2
(-850 1350);
DISPLAY 0.872340 (-850 1350);
PAINT GREEN (-850 1350);
DISPLAY INVISIBLE (-850 1350);
FORCEPROP 2 LAST PATH I76
J 2
(-1125 1500);
DISPLAY 1.021277 (-1125 1500);
DISPLAY INVISIBLE (-1125 1500);
FORCEADD Q_RES..1
(350 1450);
FORCEPROP 1 LAST LOCATION R4180
J 0
(150 1450);
DISPLAY 0.638298 (150 1450);
FORCEPROP 0 LAST $SEC 1
J 0
(700 1500);
DISPLAY 0.680851 (700 1500);
PAINT MONO (700 1500);
DISPLAY INVISIBLE (700 1500);
FORCEPROP 0 LAST CDS_SEC 1
J 0
(700 1500);
DISPLAY 1.021277 (700 1500);
DISPLAY INVISIBLE (700 1500);
FORCEPROP 1 LASTPIN (250 1450) $PN 1
J 0
(262 1462);
DISPLAY 0.787234 (262 1462);
PAINT MONO (262 1462);
FORCEPROP 1 LASTPIN (450 1450) $PN 2
J 0
(412 1462);
DISPLAY 0.787234 (412 1462);
PAINT MONO (412 1462);
FORCEPROP 1 LAST PACK_TYPE 0402LF
J 0
(700 1450);
DISPLAY 0.638298 (700 1450);
FORCEPROP 1 LAST TOLERANCE 1%
J 0
(600 1450);
DISPLAY 0.638298 (600 1450);
FORCEPROP 1 LAST WATTAGE 1/16W
J 2
(0 1450);
DISPLAY 0.638298 (0 1450);
FORCEPROP 1 LAST MATERIAL CHIP
J 0
(25 1450);
DISPLAY 0.638298 (25 1450);
FORCEPROP 1 LAST VALUE 33.2
J 2
(575 1450);
DISPLAY 0.638298 (575 1450);
FORCEPROP 2 LAST CDS_LIB pure_quanta
J 0
(350 1450);
DISPLAY INVISIBLE (350 1450);
FORCEPROP 1 LAST PATH I77
J 0
(300 1600);
DISPLAY 0.978723 (300 1600);
PAINT WHITE (300 1600);
DISPLAY INVISIBLE (300 1600);
FORCEPROP 1 LAST PART_NUMBER CS03322FB03
J 0
(175 1650);
DISPLAY 0.638298 (175 1650);
DISPLAY INVISIBLE (175 1650);
FORCEADD Q_RES..1
(350 1600);
FORCEPROP 1 LAST LOCATION R4183
J 0
(150 1600);
DISPLAY 0.638298 (150 1600);
FORCEPROP 0 LAST $SEC 1
J 0
(700 1650);
DISPLAY 0.680851 (700 1650);
PAINT MONO (700 1650);
DISPLAY INVISIBLE (700 1650);
FORCEPROP 0 LAST CDS_SEC 1
J 0
(700 1650);
DISPLAY 1.021277 (700 1650);
DISPLAY INVISIBLE (700 1650);
FORCEPROP 1 LASTPIN (250 1600) $PN 1
J 0
(262 1612);
DISPLAY 0.787234 (262 1612);
PAINT MONO (262 1612);
FORCEPROP 1 LASTPIN (450 1600) $PN 2
J 0
(412 1612);
DISPLAY 0.787234 (412 1612);
PAINT MONO (412 1612);
FORCEPROP 1 LAST WATTAGE 1/16W
J 2
(0 1600);
DISPLAY 0.638298 (0 1600);
FORCEPROP 1 LAST MATERIAL CHIP
J 0
(25 1600);
DISPLAY 0.638298 (25 1600);
FORCEPROP 1 LAST TOLERANCE 1%
J 0
(600 1600);
DISPLAY 0.638298 (600 1600);
FORCEPROP 1 LAST VALUE 33.2
J 2
(575 1600);
DISPLAY 0.638298 (575 1600);
FORCEPROP 1 LAST PACK_TYPE 0402LF
J 0
(700 1600);
DISPLAY 0.638298 (700 1600);
FORCEPROP 2 LAST CDS_LIB pure_quanta
J 0
(350 1600);
DISPLAY INVISIBLE (350 1600);
FORCEPROP 1 LAST PATH I78
J 0
(300 1750);
DISPLAY 0.978723 (300 1750);
PAINT WHITE (300 1750);
DISPLAY INVISIBLE (300 1750);
FORCEPROP 1 LAST PART_NUMBER CS03322FB03
J 0
(225 1700);
DISPLAY 0.638298 (225 1700);
DISPLAY INVISIBLE (225 1700);
FORCEADD Q_RES..1
(350 1300);
FORCEPROP 1 LAST LOCATION R4215
J 0
(150 1300);
DISPLAY 0.638298 (150 1300);
FORCEPROP 0 LAST $SEC 1
J 0
(650 1350);
DISPLAY 0.680851 (650 1350);
PAINT MONO (650 1350);
DISPLAY INVISIBLE (650 1350);
FORCEPROP 0 LAST CDS_SEC 1
J 0
(650 1350);
DISPLAY 1.021277 (650 1350);
DISPLAY INVISIBLE (650 1350);
FORCEPROP 1 LASTPIN (250 1300) $PN 1
J 0
(262 1312);
DISPLAY 0.787234 (262 1312);
PAINT MONO (262 1312);
FORCEPROP 1 LASTPIN (450 1300) $PN 2
J 0
(412 1312);
DISPLAY 0.787234 (412 1312);
PAINT MONO (412 1312);
FORCEPROP 1 LAST VALUE 0
J 2
(500 1300);
DISPLAY 0.574468 (500 1300);
FORCEPROP 1 LAST MATERIAL CHIP
J 0
(525 1300);
DISPLAY 0.574468 (525 1300);
FORCEPROP 1 LAST PACK_TYPE 0402LF
J 0
(650 1300);
DISPLAY 0.574468 (650 1300);
FORCEPROP 2 LAST CDS_LIB pure_quanta
J 0
(350 1300);
DISPLAY INVISIBLE (350 1300);
FORCEPROP 1 LAST WATTAGE 1/16W
J 2
(425 1225);
DISPLAY 0.723404 (425 1225);
PAINT SKYBLUE (425 1225);
DISPLAY INVISIBLE (425 1225);
FORCEPROP 1 LAST TOLERANCE 5%
J 0
(150 1225);
DISPLAY 0.723404 (150 1225);
PAINT SKYBLUE (150 1225);
DISPLAY INVISIBLE (150 1225);
FORCEPROP 1 LAST PATH I79
J 0
(300 1450);
DISPLAY 0.978723 (300 1450);
PAINT WHITE (300 1450);
DISPLAY INVISIBLE (300 1450);
FORCEPROP 1 LAST PART_NUMBER CS00002JB13
J 0
(75 1175);
DISPLAY 0.723404 (75 1175);
PAINT WHITE (75 1175);
DISPLAY INVISIBLE (75 1175);
FORCEADD UNIVERSAL_GND..1
(4200 775);
FORCEPROP 3 LASTPIN (4200 825) SIG_NAME GND\g
J 0
(4210 835);
DISPLAY 0.659574 (4210 835);
PAINT MONO (4210 835);
DISPLAY INVISIBLE (4210 835);
FORCEPROP 2 LAST CDS_LIB pure_quanta_power
J 0
(4200 775);
PAINT MONO (4200 775);
DISPLAY INVISIBLE (4200 775);
FORCEPROP 1 LAST HDL_POWER GND
J 1
(4225 700);
DISPLAY 0.872340 (4225 700);
PAINT GREEN (4225 700);
DISPLAY INVISIBLE (4225 700);
FORCEPROP 1 LAST PATH I80
J 0
(4275 775);
DISPLAY 0.872340 (4275 775);
PAINT AQUA (4275 775);
DISPLAY INVISIBLE (4275 775);
FORCEADD Q_RES..2
(4200 1000);
FORCEPROP 1 LAST LOCATION R4199
J 0
(4245 1125);
DISPLAY 0.638298 (4245 1125);
FORCEPROP 0 LAST $SEC 1
J 0
(4250 1175);
DISPLAY 0.680851 (4250 1175);
PAINT MONO (4250 1175);
DISPLAY INVISIBLE (4250 1175);
FORCEPROP 0 LAST CDS_SEC 1
J 0
(4250 1175);
DISPLAY 1.021277 (4250 1175);
DISPLAY INVISIBLE (4250 1175);
FORCEPROP 1 LASTPIN (4200 1100) $PN 1
J 0
(4205 1062);
DISPLAY 0.787234 (4205 1062);
PAINT MONO (4205 1062);
FORCEPROP 1 LASTPIN (4200 900) $PN 2
J 0
(4205 910);
DISPLAY 0.787234 (4205 910);
PAINT MONO (4205 910);
FORCEPROP 1 LAST TOLERANCE 1%
J 0
(4245 1025);
DISPLAY 0.638298 (4245 1025);
FORCEPROP 1 LAST WATTAGE 1/16W
J 0
(4240 975);
DISPLAY 0.638298 (4240 975);
FORCEPROP 1 LAST VALUE 1K
J 0
(4245 1075);
DISPLAY 0.638298 (4245 1075);
FORCEPROP 1 LAST PACK_TYPE 0402LF
J 0
(4240 875);
DISPLAY 0.638298 (4240 875);
FORCEPROP 1 LAST MATERIAL CHIP
J 0
(4240 925);
DISPLAY 0.638298 (4240 925);
FORCEPROP 2 LAST CDS_LIB pure_quanta
J 0
(4200 1000);
DISPLAY INVISIBLE (4200 1000);
FORCEPROP 1 LAST PATH I81
J 0
(4250 1175);
DISPLAY 0.978723 (4250 1175);
PAINT WHITE (4250 1175);
DISPLAY INVISIBLE (4250 1175);
FORCEPROP 1 LAST PART_NUMBER CS21002FB06
J 0
(4240 825);
DISPLAY 0.638298 (4240 825);
DISPLAY INVISIBLE (4240 825);
FORCEADD Q_RES..2
(4200 1600);
FORCEPROP 1 LAST LOCATION R4198
J 0
(4245 1725);
DISPLAY 0.638298 (4245 1725);
FORCEPROP 0 LAST $SEC 1
J 0
(4250 1775);
DISPLAY 0.680851 (4250 1775);
PAINT MONO (4250 1775);
DISPLAY INVISIBLE (4250 1775);
FORCEPROP 0 LAST CDS_SEC 1
J 0
(4250 1775);
DISPLAY 1.021277 (4250 1775);
DISPLAY INVISIBLE (4250 1775);
FORCEPROP 1 LASTPIN (4200 1700) $PN 1
J 0
(4205 1662);
DISPLAY 0.787234 (4205 1662);
PAINT MONO (4205 1662);
FORCEPROP 1 LASTPIN (4200 1500) $PN 2
J 0
(4205 1510);
DISPLAY 0.787234 (4205 1510);
PAINT MONO (4205 1510);
FORCEPROP 1 LAST PACK_TYPE 0402LF
J 0
(4240 1475);
DISPLAY 0.638298 (4240 1475);
FORCEPROP 1 LAST VALUE 1K
J 0
(4245 1675);
DISPLAY 0.638298 (4245 1675);
FORCEPROP 1 LAST TOLERANCE 1%
J 0
(4245 1625);
DISPLAY 0.638298 (4245 1625);
FORCEPROP 1 LAST MATERIAL EMPTY
J 0
(4240 1525);
DISPLAY 0.638298 (4240 1525);
PAINT RED (4240 1525);
FORCEPROP 1 LAST WATTAGE 1/16W
J 0
(4240 1575);
DISPLAY 0.638298 (4240 1575);
FORCEPROP 2 LAST CDS_LIB pure_quanta
J 0
(4200 1600);
DISPLAY INVISIBLE (4200 1600);
FORCEPROP 1 LAST PATH I82
J 0
(4250 1775);
DISPLAY 0.978723 (4250 1775);
PAINT WHITE (4250 1775);
DISPLAY INVISIBLE (4250 1775);
FORCEPROP 1 LAST PART_NUMBER CS21002FB06
J 0
(4240 1425);
DISPLAY 0.638298 (4240 1425);
DISPLAY INVISIBLE (4240 1425);
FORCEADD UNIVERSAL_POWER..1
(4450 2025);
FORCEPROP 3 LASTPIN (4450 1975) SIG_NAME P3V3_AUX\g
J 0
(4460 1985);
DISPLAY 0.659574 (4460 1985);
PAINT MONO (4460 1985);
DISPLAY INVISIBLE (4460 1985);
FORCEPROP 1 LAST HDL_POWER P3V3_AUX
J 1
(4450 2075);
DISPLAY 0.872340 (4450 2075);
PAINT GREEN (4450 2075);
FORCEPROP 2 LAST CDS_LIB pure_quanta_power
J 0
(4450 2025);
PAINT MONO (4450 2025);
DISPLAY INVISIBLE (4450 2025);
FORCEPROP 1 LAST PATH I83
J 0
(4500 2050);
DISPLAY 0.872340 (4500 2050);
PAINT AQUA (4500 2050);
DISPLAY INVISIBLE (4500 2050);
FORCEADD UNIVERSAL_GND..1
(4450 775);
FORCEPROP 3 LASTPIN (4450 825) SIG_NAME GND\g
J 0
(4460 835);
DISPLAY 0.659574 (4460 835);
PAINT MONO (4460 835);
DISPLAY INVISIBLE (4460 835);
FORCEPROP 2 LAST CDS_LIB pure_quanta_power
J 0
(4450 775);
PAINT MONO (4450 775);
DISPLAY INVISIBLE (4450 775);
FORCEPROP 1 LAST HDL_POWER GND
J 1
(4475 700);
DISPLAY 0.872340 (4475 700);
PAINT GREEN (4475 700);
DISPLAY INVISIBLE (4475 700);
FORCEPROP 1 LAST PATH I84
J 0
(4525 775);
DISPLAY 0.872340 (4525 775);
PAINT AQUA (4525 775);
DISPLAY INVISIBLE (4525 775);
FORCEADD Q_RES..2
(4450 1000);
FORCEPROP 1 LAST LOCATION R4207
J 0
(4495 1125);
DISPLAY 0.638298 (4495 1125);
FORCEPROP 0 LAST $SEC 1
J 0
(4500 1175);
DISPLAY 0.680851 (4500 1175);
PAINT MONO (4500 1175);
DISPLAY INVISIBLE (4500 1175);
FORCEPROP 0 LAST CDS_SEC 1
J 0
(4500 1175);
DISPLAY 1.021277 (4500 1175);
DISPLAY INVISIBLE (4500 1175);
FORCEPROP 1 LASTPIN (4450 1100) $PN 1
J 0
(4455 1062);
DISPLAY 0.787234 (4455 1062);
PAINT MONO (4455 1062);
FORCEPROP 1 LASTPIN (4450 900) $PN 2
J 0
(4455 910);
DISPLAY 0.787234 (4455 910);
PAINT MONO (4455 910);
FORCEPROP 1 LAST TOLERANCE 1%
J 0
(4495 1025);
DISPLAY 0.638298 (4495 1025);
FORCEPROP 1 LAST VALUE 1K
J 0
(4495 1075);
DISPLAY 0.638298 (4495 1075);
FORCEPROP 1 LAST WATTAGE 1/16W
J 0
(4490 975);
DISPLAY 0.638298 (4490 975);
FORCEPROP 1 LAST PACK_TYPE 0402LF
J 0
(4490 875);
DISPLAY 0.638298 (4490 875);
FORCEPROP 1 LAST MATERIAL CHIP
J 0
(4490 925);
DISPLAY 0.638298 (4490 925);
FORCEPROP 2 LAST CDS_LIB pure_quanta
J 0
(4450 1000);
DISPLAY INVISIBLE (4450 1000);
FORCEPROP 1 LAST PATH I85
J 0
(4500 1175);
DISPLAY 0.978723 (4500 1175);
PAINT WHITE (4500 1175);
DISPLAY INVISIBLE (4500 1175);
FORCEPROP 1 LAST PART_NUMBER CS21002FB06
J 0
(4490 825);
DISPLAY 0.638298 (4490 825);
DISPLAY INVISIBLE (4490 825);
FORCEADD Q_RES..2
(4450 1600);
FORCEPROP 1 LAST LOCATION R4206
J 0
(4495 1725);
DISPLAY 0.638298 (4495 1725);
FORCEPROP 0 LAST $SEC 1
J 0
(4500 1775);
DISPLAY 0.680851 (4500 1775);
PAINT MONO (4500 1775);
DISPLAY INVISIBLE (4500 1775);
FORCEPROP 0 LAST CDS_SEC 1
J 0
(4500 1775);
DISPLAY 1.021277 (4500 1775);
DISPLAY INVISIBLE (4500 1775);
FORCEPROP 1 LASTPIN (4450 1700) $PN 1
J 0
(4455 1662);
DISPLAY 0.787234 (4455 1662);
PAINT MONO (4455 1662);
FORCEPROP 1 LASTPIN (4450 1500) $PN 2
J 0
(4455 1510);
DISPLAY 0.787234 (4455 1510);
PAINT MONO (4455 1510);
FORCEPROP 1 LAST TOLERANCE 1%
J 0
(4495 1625);
DISPLAY 0.638298 (4495 1625);
FORCEPROP 1 LAST VALUE 1K
J 0
(4495 1675);
DISPLAY 0.638298 (4495 1675);
FORCEPROP 1 LAST WATTAGE 1/16W
J 0
(4490 1575);
DISPLAY 0.638298 (4490 1575);
FORCEPROP 1 LAST MATERIAL EMPTY
J 0
(4490 1525);
DISPLAY 0.638298 (4490 1525);
PAINT RED (4490 1525);
FORCEPROP 1 LAST PACK_TYPE 0402LF
J 0
(4490 1475);
DISPLAY 0.638298 (4490 1475);
FORCEPROP 2 LAST CDS_LIB pure_quanta
J 0
(4450 1600);
DISPLAY INVISIBLE (4450 1600);
FORCEPROP 1 LAST PATH I86
J 0
(4500 1775);
DISPLAY 0.978723 (4500 1775);
PAINT WHITE (4500 1775);
DISPLAY INVISIBLE (4500 1775);
FORCEPROP 1 LAST PART_NUMBER CS21002FB06
J 0
(4490 1425);
DISPLAY 0.638298 (4490 1425);
DISPLAY INVISIBLE (4490 1425);
FORCEADD Q_RES..2
(3950 1000);
FORCEPROP 1 LAST LOCATION R4191
J 0
(3995 1125);
DISPLAY 0.638298 (3995 1125);
FORCEPROP 0 LAST $SEC 1
J 0
(4000 1175);
DISPLAY 0.680851 (4000 1175);
PAINT MONO (4000 1175);
DISPLAY INVISIBLE (4000 1175);
FORCEPROP 0 LAST CDS_SEC 1
J 0
(4000 1175);
DISPLAY 1.021277 (4000 1175);
DISPLAY INVISIBLE (4000 1175);
FORCEPROP 1 LASTPIN (3950 1100) $PN 1
J 0
(3955 1062);
DISPLAY 0.787234 (3955 1062);
PAINT MONO (3955 1062);
FORCEPROP 1 LASTPIN (3950 900) $PN 2
J 0
(3955 910);
DISPLAY 0.787234 (3955 910);
PAINT MONO (3955 910);
FORCEPROP 1 LAST PACK_TYPE 0402LF
J 0
(3990 875);
DISPLAY 0.638298 (3990 875);
FORCEPROP 1 LAST MATERIAL CHIP
J 0
(3990 925);
DISPLAY 0.638298 (3990 925);
FORCEPROP 1 LAST VALUE 1K
J 0
(3995 1075);
DISPLAY 0.638298 (3995 1075);
FORCEPROP 1 LAST TOLERANCE 1%
J 0
(3995 1025);
DISPLAY 0.638298 (3995 1025);
FORCEPROP 1 LAST WATTAGE 1/16W
J 0
(3990 975);
DISPLAY 0.638298 (3990 975);
FORCEPROP 2 LAST CDS_LIB pure_quanta
J 0
(3950 1000);
DISPLAY INVISIBLE (3950 1000);
FORCEPROP 1 LAST PATH I89
J 0
(4000 1175);
DISPLAY 0.978723 (4000 1175);
PAINT WHITE (4000 1175);
DISPLAY INVISIBLE (4000 1175);
FORCEPROP 1 LAST PART_NUMBER CS21002FB06
J 0
(3990 825);
DISPLAY 0.638298 (3990 825);
DISPLAY INVISIBLE (3990 825);
FORCEADD UNIVERSAL_GND..1
(3950 775);
FORCEPROP 3 LASTPIN (3950 825) SIG_NAME GND\g
J 0
(3960 835);
DISPLAY 0.659574 (3960 835);
PAINT MONO (3960 835);
DISPLAY INVISIBLE (3960 835);
FORCEPROP 2 LAST CDS_LIB pure_quanta_power
J 0
(3950 775);
PAINT MONO (3950 775);
DISPLAY INVISIBLE (3950 775);
FORCEPROP 1 LAST HDL_POWER GND
J 1
(3975 700);
DISPLAY 0.872340 (3975 700);
PAINT GREEN (3975 700);
DISPLAY INVISIBLE (3975 700);
FORCEPROP 1 LAST PATH I90
J 0
(4025 775);
DISPLAY 0.872340 (4025 775);
PAINT AQUA (4025 775);
DISPLAY INVISIBLE (4025 775);
FORCEADD Q_RES..2
(3950 1600);
FORCEPROP 1 LAST LOCATION R4190
J 0
(3995 1725);
DISPLAY 0.638298 (3995 1725);
FORCEPROP 0 LAST $SEC 1
J 0
(4000 1775);
DISPLAY 0.680851 (4000 1775);
PAINT MONO (4000 1775);
DISPLAY INVISIBLE (4000 1775);
FORCEPROP 0 LAST CDS_SEC 1
J 0
(4000 1775);
DISPLAY 1.021277 (4000 1775);
DISPLAY INVISIBLE (4000 1775);
FORCEPROP 1 LASTPIN (3950 1700) $PN 1
J 0
(3955 1662);
DISPLAY 0.787234 (3955 1662);
PAINT MONO (3955 1662);
FORCEPROP 1 LASTPIN (3950 1500) $PN 2
J 0
(3955 1510);
DISPLAY 0.787234 (3955 1510);
PAINT MONO (3955 1510);
FORCEPROP 1 LAST MATERIAL EMPTY
J 0
(3990 1525);
DISPLAY 0.638298 (3990 1525);
PAINT RED (3990 1525);
FORCEPROP 1 LAST TOLERANCE 1%
J 0
(3995 1625);
DISPLAY 0.638298 (3995 1625);
FORCEPROP 1 LAST VALUE 1K
J 0
(3995 1675);
DISPLAY 0.638298 (3995 1675);
FORCEPROP 1 LAST WATTAGE 1/16W
J 0
(3990 1575);
DISPLAY 0.638298 (3990 1575);
FORCEPROP 1 LAST PACK_TYPE 0402LF
J 0
(3990 1475);
DISPLAY 0.638298 (3990 1475);
FORCEPROP 2 LAST CDS_LIB pure_quanta
J 0
(3950 1600);
DISPLAY INVISIBLE (3950 1600);
FORCEPROP 1 LAST PATH I91
J 0
(4000 1775);
DISPLAY 0.978723 (4000 1775);
PAINT WHITE (4000 1775);
DISPLAY INVISIBLE (4000 1775);
FORCEPROP 1 LAST PART_NUMBER CS21002FB06
J 0
(3990 1425);
DISPLAY 0.638298 (3990 1425);
DISPLAY INVISIBLE (3990 1425);
FORCEADD UNIVERSAL_POWER..1
(4400 550);
FORCEPROP 3 LASTPIN (4400 500) SIG_NAME P3V3_AUX\g
J 0
(4410 510);
DISPLAY 0.659574 (4410 510);
PAINT MONO (4410 510);
DISPLAY INVISIBLE (4410 510);
FORCEPROP 1 LAST HDL_POWER P3V3_AUX
J 1
(4400 600);
DISPLAY 0.872340 (4400 600);
PAINT GREEN (4400 600);
FORCEPROP 2 LAST CDS_LIB pure_quanta_power
J 0
(4400 550);
PAINT MONO (4400 550);
DISPLAY INVISIBLE (4400 550);
FORCEPROP 1 LAST PATH I93
J 0
(4450 575);
DISPLAY 0.872340 (4450 575);
PAINT AQUA (4450 575);
DISPLAY INVISIBLE (4450 575);
FORCEADD Q_RES..2
(4400 125);
FORCEPROP 1 LAST LOCATION R4204
J 0
(4445 250);
DISPLAY 0.638298 (4445 250);
FORCEPROP 0 LAST $SEC 1
J 0
(4450 300);
DISPLAY 0.680851 (4450 300);
PAINT MONO (4450 300);
DISPLAY INVISIBLE (4450 300);
FORCEPROP 0 LAST CDS_SEC 1
J 0
(4450 300);
DISPLAY 1.021277 (4450 300);
DISPLAY INVISIBLE (4450 300);
FORCEPROP 1 LASTPIN (4400 225) $PN 1
J 0
(4405 187);
DISPLAY 0.787234 (4405 187);
PAINT MONO (4405 187);
FORCEPROP 1 LASTPIN (4400 25) $PN 2
J 0
(4405 35);
DISPLAY 0.787234 (4405 35);
PAINT MONO (4405 35);
FORCEPROP 1 LAST MATERIAL EMPTY
J 0
(4440 50);
DISPLAY 0.638298 (4440 50);
PAINT RED (4440 50);
FORCEPROP 1 LAST TOLERANCE 1%
J 0
(4445 150);
DISPLAY 0.638298 (4445 150);
FORCEPROP 1 LAST PACK_TYPE 0402LF
J 0
(4440 0);
DISPLAY 0.638298 (4440 0);
FORCEPROP 1 LAST VALUE 1K
J 0
(4445 200);
DISPLAY 0.638298 (4445 200);
FORCEPROP 1 LAST WATTAGE 1/16W
J 0
(4440 100);
DISPLAY 0.638298 (4440 100);
FORCEPROP 2 LAST CDS_LIB pure_quanta
J 0
(4400 125);
DISPLAY INVISIBLE (4400 125);
FORCEPROP 1 LAST PATH I94
J 0
(4450 300);
DISPLAY 0.978723 (4450 300);
PAINT WHITE (4450 300);
DISPLAY INVISIBLE (4450 300);
FORCEPROP 1 LAST PART_NUMBER CS21002FB06
J 0
(4440 -50);
DISPLAY 0.638298 (4440 -50);
DISPLAY INVISIBLE (4440 -50);
FORCEADD Q_RES..2
(4150 125);
FORCEPROP 1 LAST LOCATION R4196
J 0
(4195 250);
DISPLAY 0.638298 (4195 250);
FORCEPROP 0 LAST $SEC 1
J 0
(4200 300);
DISPLAY 0.680851 (4200 300);
PAINT MONO (4200 300);
DISPLAY INVISIBLE (4200 300);
FORCEPROP 0 LAST CDS_SEC 1
J 0
(4200 300);
DISPLAY 1.021277 (4200 300);
DISPLAY INVISIBLE (4200 300);
FORCEPROP 1 LASTPIN (4150 225) $PN 1
J 0
(4155 187);
DISPLAY 0.787234 (4155 187);
PAINT MONO (4155 187);
FORCEPROP 1 LASTPIN (4150 25) $PN 2
J 0
(4155 35);
DISPLAY 0.787234 (4155 35);
PAINT MONO (4155 35);
FORCEPROP 1 LAST PACK_TYPE 0402LF
J 0
(4190 0);
DISPLAY 0.638298 (4190 0);
FORCEPROP 1 LAST MATERIAL EMPTY
J 0
(4190 50);
DISPLAY 0.638298 (4190 50);
PAINT RED (4190 50);
FORCEPROP 1 LAST VALUE 1K
J 0
(4195 200);
DISPLAY 0.638298 (4195 200);
FORCEPROP 1 LAST WATTAGE 1/16W
J 0
(4190 100);
DISPLAY 0.638298 (4190 100);
FORCEPROP 1 LAST TOLERANCE 1%
J 0
(4195 150);
DISPLAY 0.638298 (4195 150);
FORCEPROP 2 LAST CDS_LIB pure_quanta
J 0
(4150 125);
DISPLAY INVISIBLE (4150 125);
FORCEPROP 1 LAST PATH I95
J 0
(4200 300);
DISPLAY 0.978723 (4200 300);
PAINT WHITE (4200 300);
DISPLAY INVISIBLE (4200 300);
FORCEPROP 1 LAST PART_NUMBER CS21002FB06
J 0
(4190 -50);
DISPLAY 0.638298 (4190 -50);
DISPLAY INVISIBLE (4190 -50);
FORCEADD Q_RES..2
(4400 -475);
FORCEPROP 1 LAST LOCATION R4205
J 0
(4445 -350);
DISPLAY 0.638298 (4445 -350);
FORCEPROP 0 LAST $SEC 1
J 0
(4450 -300);
DISPLAY 0.680851 (4450 -300);
PAINT MONO (4450 -300);
DISPLAY INVISIBLE (4450 -300);
FORCEPROP 0 LAST CDS_SEC 1
J 0
(4450 -300);
DISPLAY 1.021277 (4450 -300);
DISPLAY INVISIBLE (4450 -300);
FORCEPROP 1 LASTPIN (4400 -375) $PN 1
J 0
(4405 -413);
DISPLAY 0.787234 (4405 -413);
PAINT MONO (4405 -413);
FORCEPROP 1 LASTPIN (4400 -575) $PN 2
J 0
(4405 -565);
DISPLAY 0.787234 (4405 -565);
PAINT MONO (4405 -565);
FORCEPROP 1 LAST TOLERANCE 1%
J 0
(4445 -450);
DISPLAY 0.638298 (4445 -450);
FORCEPROP 1 LAST VALUE 1K
J 0
(4445 -400);
DISPLAY 0.638298 (4445 -400);
FORCEPROP 1 LAST WATTAGE 1/16W
J 0
(4440 -500);
DISPLAY 0.638298 (4440 -500);
FORCEPROP 1 LAST PACK_TYPE 0402LF
J 0
(4440 -600);
DISPLAY 0.638298 (4440 -600);
FORCEPROP 1 LAST MATERIAL CHIP
J 0
(4440 -550);
DISPLAY 0.638298 (4440 -550);
FORCEPROP 2 LAST CDS_LIB pure_quanta
J 0
(4400 -475);
DISPLAY INVISIBLE (4400 -475);
FORCEPROP 1 LAST PATH I96
J 0
(4450 -300);
DISPLAY 0.978723 (4450 -300);
PAINT WHITE (4450 -300);
DISPLAY INVISIBLE (4450 -300);
FORCEPROP 1 LAST PART_NUMBER CS21002FB06
J 0
(4440 -650);
DISPLAY 0.638298 (4440 -650);
DISPLAY INVISIBLE (4440 -650);
FORCEADD UNIVERSAL_GND..1
(4400 -700);
FORCEPROP 3 LASTPIN (4400 -650) SIG_NAME GND\g
J 0
(4410 -640);
DISPLAY 0.659574 (4410 -640);
PAINT MONO (4410 -640);
DISPLAY INVISIBLE (4410 -640);
FORCEPROP 2 LAST CDS_LIB pure_quanta_power
J 0
(4400 -700);
PAINT MONO (4400 -700);
DISPLAY INVISIBLE (4400 -700);
FORCEPROP 1 LAST HDL_POWER GND
J 1
(4425 -775);
DISPLAY 0.872340 (4425 -775);
PAINT GREEN (4425 -775);
DISPLAY INVISIBLE (4425 -775);
FORCEPROP 1 LAST PATH I97
J 0
(4475 -700);
DISPLAY 0.872340 (4475 -700);
PAINT AQUA (4475 -700);
DISPLAY INVISIBLE (4475 -700);
FORCEADD Q_RES..2
(4150 -475);
FORCEPROP 1 LAST LOCATION R4197
J 0
(4195 -350);
DISPLAY 0.638298 (4195 -350);
FORCEPROP 0 LAST $SEC 1
J 0
(4200 -300);
DISPLAY 0.680851 (4200 -300);
PAINT MONO (4200 -300);
DISPLAY INVISIBLE (4200 -300);
FORCEPROP 0 LAST CDS_SEC 1
J 0
(4200 -300);
DISPLAY 1.021277 (4200 -300);
DISPLAY INVISIBLE (4200 -300);
FORCEPROP 1 LASTPIN (4150 -375) $PN 1
J 0
(4155 -413);
DISPLAY 0.787234 (4155 -413);
PAINT MONO (4155 -413);
FORCEPROP 1 LASTPIN (4150 -575) $PN 2
J 0
(4155 -565);
DISPLAY 0.787234 (4155 -565);
PAINT MONO (4155 -565);
FORCEPROP 1 LAST WATTAGE 1/16W
J 0
(4190 -500);
DISPLAY 0.638298 (4190 -500);
FORCEPROP 1 LAST VALUE 1K
J 0
(4195 -400);
DISPLAY 0.638298 (4195 -400);
FORCEPROP 1 LAST PACK_TYPE 0402LF
J 0
(4190 -600);
DISPLAY 0.638298 (4190 -600);
FORCEPROP 1 LAST MATERIAL CHIP
J 0
(4190 -550);
DISPLAY 0.638298 (4190 -550);
FORCEPROP 1 LAST TOLERANCE 1%
J 0
(4195 -450);
DISPLAY 0.638298 (4195 -450);
FORCEPROP 2 LAST CDS_LIB pure_quanta
J 0
(4150 -475);
DISPLAY INVISIBLE (4150 -475);
FORCEPROP 1 LAST PATH I98
J 0
(4200 -300);
DISPLAY 0.978723 (4200 -300);
PAINT WHITE (4200 -300);
DISPLAY INVISIBLE (4200 -300);
FORCEPROP 1 LAST PART_NUMBER CS21002FB06
J 0
(4190 -650);
DISPLAY 0.638298 (4190 -650);
DISPLAY INVISIBLE (4190 -650);
FORCEADD UNIVERSAL_GND..1
(4150 -700);
FORCEPROP 3 LASTPIN (4150 -650) SIG_NAME GND\g
J 0
(4160 -640);
DISPLAY 0.659574 (4160 -640);
PAINT MONO (4160 -640);
DISPLAY INVISIBLE (4160 -640);
FORCEPROP 2 LAST CDS_LIB pure_quanta_power
J 0
(4150 -700);
PAINT MONO (4150 -700);
DISPLAY INVISIBLE (4150 -700);
FORCEPROP 1 LAST HDL_POWER GND
J 1
(4175 -775);
DISPLAY 0.872340 (4175 -775);
PAINT GREEN (4175 -775);
DISPLAY INVISIBLE (4175 -775);
FORCEPROP 1 LAST PATH I99
J 0
(4225 -700);
DISPLAY 0.872340 (4225 -700);
PAINT AQUA (4225 -700);
DISPLAY INVISIBLE (4225 -700);
FORCEADD DNS..2
(-350 -2650);
PAINT RED (-350 -2650);
FORCEPROP 2 LAST CDS_LIB mstr_misc
J 0
(-350 -2650);
DISPLAY INVISIBLE (-350 -2650);
FORCEPROP 1 LAST COMMENT_BODY TRUE
J 0
(-350 -2650);
DISPLAY INVISIBLE (-350 -2650);
FORCEADD DNS..2
(3900 100);
PAINT RED (3900 100);
FORCEPROP 2 LAST CDS_LIB mstr_misc
J 0
(3900 100);
PAINT MONO (3900 100);
DISPLAY INVISIBLE (3900 100);
FORCEPROP 1 LAST COMMENT_BODY TRUE
J 0
(3900 100);
DISPLAY INVISIBLE (3900 100);
FORCEADD DNS..2
(3825 -2850);
PAINT RED (3825 -2850);
FORCEPROP 2 LAST CDS_LIB mstr_misc
J 0
(3825 -2850);
PAINT MONO (3825 -2850);
DISPLAY INVISIBLE (3825 -2850);
FORCEPROP 1 LAST COMMENT_BODY TRUE
J 0
(3825 -2850);
DISPLAY INVISIBLE (3825 -2850);
FORCEADD DNS..2
(4075 -2850);
PAINT RED (4075 -2850);
FORCEPROP 2 LAST CDS_LIB mstr_misc
J 0
(4075 -2850);
PAINT MONO (4075 -2850);
DISPLAY INVISIBLE (4075 -2850);
FORCEPROP 1 LAST COMMENT_BODY TRUE
J 0
(4075 -2850);
DISPLAY INVISIBLE (4075 -2850);
FORCEADD DNS..2
(4330 -2830);
PAINT RED (4330 -2830);
FORCEPROP 2 LAST CDS_LIB mstr_misc
J 0
(4330 -2830);
PAINT MONO (4330 -2830);
DISPLAY INVISIBLE (4330 -2830);
FORCEPROP 1 LAST COMMENT_BODY TRUE
J 0
(4330 -2830);
DISPLAY INVISIBLE (4330 -2830);
FORCEADD DNS..2
(3875 -1375);
PAINT RED (3875 -1375);
FORCEPROP 2 LAST CDS_LIB mstr_misc
J 0
(3875 -1375);
PAINT MONO (3875 -1375);
DISPLAY INVISIBLE (3875 -1375);
FORCEPROP 1 LAST COMMENT_BODY TRUE
J 0
(3875 -1375);
DISPLAY INVISIBLE (3875 -1375);
FORCEADD DNS..2
(4125 -1375);
PAINT RED (4125 -1375);
FORCEPROP 2 LAST CDS_LIB mstr_misc
J 0
(4125 -1375);
PAINT MONO (4125 -1375);
DISPLAY INVISIBLE (4125 -1375);
FORCEPROP 1 LAST COMMENT_BODY TRUE
J 0
(4125 -1375);
DISPLAY INVISIBLE (4125 -1375);
FORCEADD DNS..2
(4380 -1355);
PAINT RED (4380 -1355);
FORCEPROP 2 LAST CDS_LIB mstr_misc
J 0
(4380 -1355);
PAINT MONO (4380 -1355);
DISPLAY INVISIBLE (4380 -1355);
FORCEPROP 1 LAST COMMENT_BODY TRUE
J 0
(4380 -1355);
DISPLAY INVISIBLE (4380 -1355);
FORCEADD DNS..2
(4150 100);
PAINT RED (4150 100);
FORCEPROP 2 LAST CDS_LIB mstr_misc
J 0
(4150 100);
PAINT MONO (4150 100);
DISPLAY INVISIBLE (4150 100);
FORCEPROP 1 LAST COMMENT_BODY TRUE
J 0
(4150 100);
DISPLAY INVISIBLE (4150 100);
FORCEADD DNS..2
(4405 120);
PAINT RED (4405 120);
FORCEPROP 2 LAST CDS_LIB mstr_misc
J 0
(4405 120);
PAINT MONO (4405 120);
DISPLAY INVISIBLE (4405 120);
FORCEPROP 1 LAST COMMENT_BODY TRUE
J 0
(4405 120);
DISPLAY INVISIBLE (4405 120);
FORCEADD DNS..2
(3950 1575);
PAINT RED (3950 1575);
FORCEPROP 2 LAST CDS_LIB mstr_misc
J 0
(3950 1575);
PAINT MONO (3950 1575);
DISPLAY INVISIBLE (3950 1575);
FORCEPROP 1 LAST COMMENT_BODY TRUE
J 0
(3950 1575);
DISPLAY INVISIBLE (3950 1575);
FORCEADD DNS..2
(4200 1575);
PAINT RED (4200 1575);
FORCEPROP 2 LAST CDS_LIB mstr_misc
J 0
(4200 1575);
PAINT MONO (4200 1575);
DISPLAY INVISIBLE (4200 1575);
FORCEPROP 1 LAST COMMENT_BODY TRUE
J 0
(4200 1575);
DISPLAY INVISIBLE (4200 1575);
FORCEADD DNS..2
(4455 1595);
PAINT RED (4455 1595);
FORCEPROP 2 LAST CDS_LIB mstr_misc
J 0
(4455 1595);
PAINT MONO (4455 1595);
DISPLAY INVISIBLE (4455 1595);
FORCEPROP 1 LAST COMMENT_BODY TRUE
J 0
(4455 1595);
DISPLAY INVISIBLE (4455 1595);
FORCEADD DNS..2
(-250 300);
PAINT RED (-250 300);
FORCEPROP 2 LAST CDS_LIB mstr_misc
J 0
(-250 300);
DISPLAY INVISIBLE (-250 300);
FORCEPROP 1 LAST COMMENT_BODY TRUE
J 0
(-250 300);
DISPLAY INVISIBLE (-250 300);
FORCEADD DNS..2
(-250 -1200);
PAINT RED (-250 -1200);
FORCEPROP 2 LAST CDS_LIB mstr_misc
J 0
(-250 -1200);
DISPLAY INVISIBLE (-250 -1200);
FORCEPROP 1 LAST COMMENT_BODY TRUE
J 0
(-250 -1200);
DISPLAY INVISIBLE (-250 -1200);
FORCEADD QUANTA_TITLE_BLOCK_C..1
(6625 -4100);
FORCEPROP 0 LAST CDS_CON_LAST_MODIFIED Thu Sep 14 16:12:30 2023
J 0
(4740 -4085);
DISPLAY INVISIBLE (4740 -4085);
FORCEPROP 1 LAST CUSTOM_TXT_CDS <CON_LAST_MODIFIED>
J 0
(4740 -4085);
DISPLAY 0.978723 (4740 -4085);
FORCEPROP 2 LAST CUSTOM_TXT_CDS <XR_PAGE_TITLE>
J 0
(-1265 1150);
DISPLAY 0.638298 (-1265 1150);
PAINT PINK (-1265 1150);
DISPLAY INVISIBLE (-1265 1150);
FORCEPROP 1 LAST CUSTOM_TXT_CDS <NAME_2>
J 0
(3450 -4050);
FORCEPROP 1 LAST CUSTOM_TXT_CDS <NAME_1>
J 0
(3450 -3925);
FORCEPROP 1 LAST CUSTOM_TXT_CDS <Q_NUMBER>
J 0
(5222 -3997);
DISPLAY 1.212766 (5222 -3997);
FORCEPROP 1 LAST CUSTOM_TXT_CDS <Q_PROJ>
J 0
(4243 -3998);
DISPLAY 1.212766 (4243 -3998);
FORCEPROP 1 LAST CUSTOM_TXT_CDS <Q_REV>
J 0
(6441 -3997);
DISPLAY 1.212766 (6441 -3997);
FORCEPROP 1 LAST CUSTOM_TXT_CDS <CON_PAGE_NUM> OF <CON_TOTAL_PAGES>
J 0
(6179 -4082);
DISPLAY 0.978723 (6179 -4082);
FORCEPROP 1 LAST Q_TITLE TEMP SENSOR - LM75
J 0
(-2675 -4050);
DISPLAY 2.446809 (-2675 -4050);
PAINT GREEN (-2675 -4050);
FORCEPROP 2 LAST PAGE_BORDER TRUE
J 0
(-1265 1150);
DISPLAY 0.638298 (-1265 1150);
PAINT PINK (-1265 1150);
DISPLAY INVISIBLE (-1265 1150);
FORCEPROP 1 LAST CDS_LMAN_SYM_OUTLINE -9475,6775,100,-125
J 0
(6625 -4100);
DISPLAY 0.468085 (6625 -4100);
PAINT GREEN (6625 -4100);
DISPLAY INVISIBLE (6625 -4100);
FORCEPROP 2 LAST CDS_LIB pure_quanta
J 0
(6625 -4100);
DISPLAY INVISIBLE (6625 -4100);
FORCEPROP 2 LAST CDS_XR_PAGE_TITLE CR-236 : @T6G_MB_LIB.T6G(SCH_1):PAGE236
J 0
(-1265 1150);
DISPLAY 0.638298 (-1265 1150);
PAINT PINK (-1265 1150);
DISPLAY INVISIBLE (-1265 1150);
FORCEPROP 1 LAST Q_DEPT BU9
J 1
(2862 -4051);
DISPLAY 1.957447 (2862 -4051);
PAINT GREEN (2862 -4051);
DISPLAY INVISIBLE (2862 -4051);
FORCEPROP 1 LAST COMMENT_BODY TRUE
J 0
(6637 -4113);
DISPLAY 0.978723 (6637 -4113);
PAINT GREEN (6637 -4113);
DISPLAY INVISIBLE (6637 -4113);
WIRE 16 -1 (3900 -575)(3900 -650);
WIRE 16 -1 (2550 375)(2550 300);
WIRE 16 -1 (1725 -325)(1625 -325);
WIRE 16 -1 (1625 -325)(1625 -400);
WIRE 16 -1 (1700 -1800)(1600 -1800);
WIRE 16 -1 (1600 -1800)(1600 -1875);
WIRE 16 -1 (2525 -1100)(2525 -1175);
WIRE 16 -1 (3875 -2050)(3875 -2125);
WIRE 16 -1 (4125 -2050)(4125 -2125);
WIRE 16 -1 (4375 -2050)(4375 -2125);
WIRE 16 -1 (1650 -3275)(1550 -3275);
WIRE 16 -1 (1550 -3275)(1550 -3350);
WIRE 16 -1 (2475 -2575)(2475 -2650);
WIRE 16 -1 (3825 -3525)(3825 -3600);
WIRE 16 -1 (4075 -3525)(4075 -3600);
WIRE 16 -1 (4325 -3525)(4325 -3600);
WIRE 16 -1 (-200 1900)(-200 1975);
WIRE 16 -1 (-250 425)(-250 500);
WIRE 16 -1 (-250 -1075)(-250 -975);
WIRE 16 -1 (-350 -2525)(-350 -2400);
WIRE 16 -1 (2600 1850)(2600 1775);
WIRE 16 -1 (1775 1150)(1675 1150);
WIRE 16 -1 (1675 1150)(1675 1075);
WIRE 16 -1 (4200 900)(4200 825);
WIRE 16 -1 (4450 900)(4450 825);
WIRE 16 -1 (3950 900)(3950 825);
WIRE 16 -1 (4400 -575)(4400 -650);
WIRE 16 -1 (4150 -575)(4150 -650);
WIRE 16 -1 (2800 -2300)(2800 -2825);
FORCEPROP 0 LAST VOLTAGE 3.3
J 0
(2800 -2538);
DISPLAY INVISIBLE (2800 -2538);
WIRE 16 -1 (2475 -2300)(2800 -2300);
WIRE 16 -1 (2800 -2825)(2400 -2825);
WIRE 16 -1 (2475 -2375)(2475 -2300);
WIRE 16 -1 (2475 -2300)(2475 -2200);
WIRE 16 -1 (2400 -3125)(4075 -3125);
FORCEPROP 0 LAST CDS_PHYS_NET_NAME TCA9539_0_ADD1
J 0
(3090 -3083);
PAINT MONO (3090 -3083);
DISPLAY INVISIBLE (3090 -3083);
FORCEPROP 2 LAST SIG_NAME U273_3_ADD1
J 0
(2615 -3115);
DISPLAY 0.553191 (2615 -3115);
PAINT WHITE (2615 -3115);
FORCEPROP 2 LASTPROP $XRERR UNIQUE?
J 0
(2375 -3115);
DISPLAY 0.638298 (2375 -3115);
PAINT MONO (2375 -3115);
DISPLAY INVISIBLE (2375 -3115);
WIRE 16 -1 (4075 -3125)(4075 -2925);
WIRE 16 -1 (4075 -3325)(4075 -3125);
WIRE 16 -1 (2400 -2975)(4325 -2975);
FORCEPROP 0 LAST CDS_PHYS_NET_NAME TCA9539_0_ADD0
J 0
(2840 -2933);
PAINT MONO (2840 -2933);
DISPLAY INVISIBLE (2840 -2933);
FORCEPROP 2 LAST SIG_NAME U273_3_ADD0
J 0
(2615 -2965);
DISPLAY 0.553191 (2615 -2965);
PAINT WHITE (2615 -2965);
FORCEPROP 2 LASTPROP $XRERR UNIQUE?
J 0
(2375 -2965);
DISPLAY 0.638298 (2375 -2965);
PAINT MONO (2375 -2965);
DISPLAY INVISIBLE (2375 -2965);
WIRE 16 -1 (4325 -2975)(4325 -2925);
WIRE 16 -1 (4325 -3325)(4325 -2975);
WIRE 16 -1 (2400 -3275)(3825 -3275);
FORCEPROP 0 LAST CDS_PHYS_NET_NAME TCA9539_0_ADD1
J 0
(3090 -3233);
PAINT MONO (3090 -3233);
DISPLAY INVISIBLE (3090 -3233);
FORCEPROP 2 LAST SIG_NAME U273_3_ADD2
J 0
(2615 -3265);
DISPLAY 0.553191 (2615 -3265);
PAINT WHITE (2615 -3265);
FORCEPROP 2 LASTPROP $XRERR UNIQUE?
J 0
(2375 -3265);
DISPLAY 0.638298 (2375 -3265);
PAINT MONO (2375 -3265);
DISPLAY INVISIBLE (2375 -3265);
WIRE 16 -1 (3825 -3275)(3825 -2925);
WIRE 16 -1 (3825 -3325)(3825 -3275);
WIRE 16 -1 (2475 -325)(3900 -325);
FORCEPROP 0 LAST CDS_PHYS_NET_NAME TCA9539_0_ADD1
J 0
(3165 -283);
PAINT MONO (3165 -283);
DISPLAY INVISIBLE (3165 -283);
FORCEPROP 2 LAST SIG_NAME U271_1_ADD2
J 0
(2690 -315);
DISPLAY 0.553191 (2690 -315);
PAINT WHITE (2690 -315);
FORCEPROP 2 LASTPROP $XRERR UNIQUE?
J 0
(2450 -315);
DISPLAY 0.638298 (2450 -315);
PAINT MONO (2450 -315);
DISPLAY INVISIBLE (2450 -315);
WIRE 16 -1 (3900 -325)(3900 25);
WIRE 16 -1 (3900 -375)(3900 -325);
WIRE 16 -1 (2475 -175)(4150 -175);
FORCEPROP 0 LAST CDS_PHYS_NET_NAME TCA9539_0_ADD1
J 0
(3165 -133);
PAINT MONO (3165 -133);
DISPLAY INVISIBLE (3165 -133);
FORCEPROP 2 LAST SIG_NAME U271_1_ADD1
J 0
(2690 -165);
DISPLAY 0.553191 (2690 -165);
PAINT WHITE (2690 -165);
FORCEPROP 2 LASTPROP $XRERR UNIQUE?
J 0
(2450 -165);
DISPLAY 0.638298 (2450 -165);
PAINT MONO (2450 -165);
DISPLAY INVISIBLE (2450 -165);
WIRE 16 -1 (4150 -175)(4150 25);
WIRE 16 -1 (4150 -375)(4150 -175);
WIRE 16 -1 (3900 225)(3900 400);
WIRE 16 -1 (3900 400)(4150 400);
WIRE 16 -1 (4400 400)(4150 400);
WIRE 16 -1 (4150 225)(4150 400);
WIRE 16 -1 (4400 500)(4400 400);
WIRE 16 -1 (4400 225)(4400 400);
WIRE 16 -1 (375 -1650)(1700 -1650);
FORCEPROP 2 LAST SIG_NAME FM_LM75_2_ALERT_N
J 0
(865 -1640);
DISPLAY 0.638298 (865 -1640);
PAINT WHITE (865 -1640);
FORCEPROP 2 LASTPROP $XRERR UNIQUE?
J 0
(625 -1640);
DISPLAY 0.638298 (625 -1640);
PAINT MONO (625 -1640);
DISPLAY INVISIBLE (625 -1640);
WIRE 16 -1 (375 -1500)(1700 -1500);
FORCEPROP 2 LAST SIG_NAME SMB_LM75_2_3V3AUX_SCL_R1
J 0
(865 -1490);
DISPLAY 0.638298 (865 -1490);
PAINT WHITE (865 -1490);
FORCEPROP 2 LASTPROP $XRERR UNIQUE?
J 0
(625 -1490);
DISPLAY 0.638298 (625 -1490);
PAINT MONO (625 -1490);
DISPLAY INVISIBLE (625 -1490);
WIRE 16 -1 (4450 1700)(4450 1875);
WIRE 16 -1 (4450 1975)(4450 1875);
WIRE 16 -1 (4450 1875)(4200 1875);
WIRE 16 -1 (4200 1700)(4200 1875);
WIRE 16 -1 (3950 1875)(4200 1875);
WIRE 16 -1 (3950 1700)(3950 1875);
WIRE 16 -1 (4325 -2725)(4325 -2550);
WIRE 16 -1 (4325 -2450)(4325 -2550);
WIRE 16 -1 (4325 -2550)(4075 -2550);
WIRE 16 -1 (3825 -2550)(4075 -2550);
WIRE 16 -1 (4075 -2725)(4075 -2550);
WIRE 16 -1 (3825 -2725)(3825 -2550);
WIRE 16 -1 (2600 2125)(2925 2125);
WIRE 16 -1 (2600 2050)(2600 2125);
WIRE 16 -1 (2600 2125)(2600 2225);
WIRE 16 -1 (2925 2125)(2925 1600);
WIRE 16 -1 (2925 1600)(2525 1600);
WIRE 16 -1 (4375 -1250)(4375 -1075);
WIRE 16 -1 (4375 -975)(4375 -1075);
WIRE 16 -1 (4375 -1075)(4125 -1075);
WIRE 16 -1 (4125 -1250)(4125 -1075);
WIRE 16 -1 (3875 -1075)(4125 -1075);
WIRE 16 -1 (3875 -1250)(3875 -1075);
WIRE 16 -1 (2525 -825)(2850 -825);
WIRE 16 -1 (2525 -900)(2525 -825);
WIRE 16 -1 (2525 -825)(2525 -725);
WIRE 16 -1 (2850 -825)(2850 -1350);
FORCEPROP 0 LAST VOLTAGE 3.3
J 0
(2850 -1063);
DISPLAY INVISIBLE (2850 -1063);
WIRE 16 -1 (2850 -1350)(2450 -1350);
WIRE 16 -1 (2875 650)(2875 125);
WIRE 16 -1 (2550 650)(2875 650);
WIRE 16 -1 (2875 125)(2475 125);
WIRE 16 -1 (2550 575)(2550 650);
WIRE 16 -1 (2550 650)(2550 750);
WIRE 16 -1 (2450 -1800)(3875 -1800);
FORCEPROP 0 LAST CDS_PHYS_NET_NAME TCA9539_0_ADD1
J 0
(3140 -1758);
PAINT MONO (3140 -1758);
DISPLAY INVISIBLE (3140 -1758);
FORCEPROP 2 LAST SIG_NAME U272_2_ADD2
J 0
(2665 -1790);
DISPLAY 0.553191 (2665 -1790);
PAINT WHITE (2665 -1790);
FORCEPROP 2 LASTPROP $XRERR UNIQUE?
J 0
(2425 -1790);
DISPLAY 0.638298 (2425 -1790);
PAINT MONO (2425 -1790);
DISPLAY INVISIBLE (2425 -1790);
WIRE 16 -1 (3875 -1800)(3875 -1450);
WIRE 16 -1 (3875 -1850)(3875 -1800);
WIRE 16 -1 (2450 -1500)(4375 -1500);
FORCEPROP 0 LAST CDS_PHYS_NET_NAME TCA9539_0_ADD0
J 0
(2890 -1458);
PAINT MONO (2890 -1458);
DISPLAY INVISIBLE (2890 -1458);
FORCEPROP 2 LAST SIG_NAME U272_2_ADD0
J 0
(2665 -1490);
DISPLAY 0.553191 (2665 -1490);
PAINT WHITE (2665 -1490);
FORCEPROP 2 LASTPROP $XRERR UNIQUE?
J 0
(2425 -1490);
DISPLAY 0.638298 (2425 -1490);
PAINT MONO (2425 -1490);
DISPLAY INVISIBLE (2425 -1490);
WIRE 16 -1 (4375 -1500)(4375 -1450);
WIRE 16 -1 (4375 -1850)(4375 -1500);
WIRE 16 -1 (450 1600)(1775 1600);
FORCEPROP 2 LAST SIG_NAME SMB_LM75_0_3V3AUX_SDA_R1
J 0
(940 1610);
DISPLAY 0.638298 (940 1610);
PAINT WHITE (940 1610);
FORCEPROP 2 LASTPROP $XRERR UNIQUE?
J 0
(700 1610);
DISPLAY 0.638298 (700 1610);
PAINT MONO (700 1610);
DISPLAY INVISIBLE (700 1610);
WIRE 16 -1 (450 1450)(1775 1450);
FORCEPROP 2 LAST SIG_NAME SMB_LM75_0_3V3AUX_SCL_R1
J 0
(940 1460);
DISPLAY 0.638298 (940 1460);
PAINT WHITE (940 1460);
FORCEPROP 2 LASTPROP $XRERR UNIQUE?
J 0
(700 1460);
DISPLAY 0.638298 (700 1460);
PAINT MONO (700 1460);
DISPLAY INVISIBLE (700 1460);
WIRE 16 -1 (2475 -25)(4400 -25);
FORCEPROP 0 LAST CDS_PHYS_NET_NAME TCA9539_0_ADD0
J 0
(2915 17);
PAINT MONO (2915 17);
DISPLAY INVISIBLE (2915 17);
FORCEPROP 2 LAST SIG_NAME U271_1_ADD0
J 0
(2690 -15);
DISPLAY 0.553191 (2690 -15);
PAINT WHITE (2690 -15);
FORCEPROP 2 LASTPROP $XRERR UNIQUE?
J 0
(2450 -15);
DISPLAY 0.638298 (2450 -15);
PAINT MONO (2450 -15);
DISPLAY INVISIBLE (2450 -15);
WIRE 16 -1 (4400 -25)(4400 25);
WIRE 16 -1 (4400 -375)(4400 -25);
WIRE 16 -1 (400 -175)(1725 -175);
FORCEPROP 2 LAST SIG_NAME FM_G751_1_ALERT_N
J 0
(890 -165);
DISPLAY 0.638298 (890 -165);
PAINT WHITE (890 -165);
FORCEPROP 2 LASTPROP $XRERR UNIQUE?
J 0
(650 -165);
DISPLAY 0.638298 (650 -165);
PAINT MONO (650 -165);
DISPLAY INVISIBLE (650 -165);
WIRE 16 -1 (2525 1150)(3950 1150);
FORCEPROP 0 LAST CDS_PHYS_NET_NAME TCA9539_0_ADD1
J 0
(3215 1192);
PAINT MONO (3215 1192);
DISPLAY INVISIBLE (3215 1192);
FORCEPROP 2 LAST SIG_NAME U270_0_ADD2
J 0
(2740 1160);
DISPLAY 0.553191 (2740 1160);
PAINT WHITE (2740 1160);
FORCEPROP 2 LASTPROP $XRERR UNIQUE?
J 0
(2500 1160);
DISPLAY 0.638298 (2500 1160);
PAINT MONO (2500 1160);
DISPLAY INVISIBLE (2500 1160);
WIRE 16 -1 (3950 1150)(3950 1500);
WIRE 16 -1 (3950 1100)(3950 1150);
WIRE 16 -1 (2525 1300)(4200 1300);
FORCEPROP 0 LAST CDS_PHYS_NET_NAME TCA9539_0_ADD1
J 0
(3215 1342);
PAINT MONO (3215 1342);
DISPLAY INVISIBLE (3215 1342);
FORCEPROP 2 LAST SIG_NAME U270_0_ADD1
J 0
(2740 1310);
DISPLAY 0.553191 (2740 1310);
PAINT WHITE (2740 1310);
FORCEPROP 2 LASTPROP $XRERR UNIQUE?
J 0
(2500 1310);
DISPLAY 0.638298 (2500 1310);
PAINT MONO (2500 1310);
DISPLAY INVISIBLE (2500 1310);
WIRE 16 -1 (4200 1300)(4200 1500);
WIRE 16 -1 (4200 1100)(4200 1300);
WIRE 16 -1 (2525 1450)(4450 1450);
FORCEPROP 0 LAST CDS_PHYS_NET_NAME TCA9539_0_ADD0
J 0
(2965 1492);
PAINT MONO (2965 1492);
DISPLAY INVISIBLE (2965 1492);
FORCEPROP 2 LAST SIG_NAME U270_0_ADD0
J 0
(2740 1460);
DISPLAY 0.553191 (2740 1460);
PAINT WHITE (2740 1460);
FORCEPROP 2 LASTPROP $XRERR UNIQUE?
J 0
(2500 1460);
DISPLAY 0.638298 (2500 1460);
PAINT MONO (2500 1460);
DISPLAY INVISIBLE (2500 1460);
WIRE 16 -1 (4450 1450)(4450 1500);
WIRE 16 -1 (4450 1100)(4450 1450);
WIRE 16 -1 (400 125)(1725 125);
FORCEPROP 2 LAST SIG_NAME SMB_LM75_1_3V3AUX_SDA_R1
J 0
(890 135);
DISPLAY 0.638298 (890 135);
PAINT WHITE (890 135);
FORCEPROP 2 LASTPROP $XRERR UNIQUE?
J 0
(650 135);
DISPLAY 0.638298 (650 135);
PAINT MONO (650 135);
DISPLAY INVISIBLE (650 135);
WIRE 16 -1 (450 1300)(1775 1300);
FORCEPROP 2 LAST SIG_NAME FM_G751_0_ALERT_N
J 0
(940 1310);
DISPLAY 0.638298 (940 1310);
PAINT WHITE (940 1310);
FORCEPROP 2 LASTPROP $XRERR UNIQUE?
J 0
(700 1310);
DISPLAY 0.638298 (700 1310);
PAINT MONO (700 1310);
DISPLAY INVISIBLE (700 1310);
WIRE 16 -1 (2450 -1650)(4125 -1650);
FORCEPROP 0 LAST CDS_PHYS_NET_NAME TCA9539_0_ADD1
J 0
(3140 -1608);
PAINT MONO (3140 -1608);
DISPLAY INVISIBLE (3140 -1608);
FORCEPROP 2 LAST SIG_NAME U272_2_ADD1
J 0
(2665 -1640);
DISPLAY 0.553191 (2665 -1640);
PAINT WHITE (2665 -1640);
FORCEPROP 2 LASTPROP $XRERR UNIQUE?
J 0
(2425 -1640);
DISPLAY 0.638298 (2425 -1640);
PAINT MONO (2425 -1640);
DISPLAY INVISIBLE (2425 -1640);
WIRE 16 -1 (4125 -1650)(4125 -1450);
WIRE 16 -1 (4125 -1850)(4125 -1650);
WIRE 16 -1 (-850 1450)(250 1450);
FORCEPROP 2 LAST SIG_NAME SMB_LM75_0_3V3AUX_SCL
J 0
(-860 1460);
DISPLAY 0.638298 (-860 1460);
PAINT WHITE (-860 1460);
WIRE 16 -1 (-900 -25)(200 -25);
FORCEPROP 2 LAST SIG_NAME SMB_LM75_1_3V3AUX_SCL
J 0
(-910 -15);
DISPLAY 0.638298 (-910 -15);
PAINT WHITE (-910 -15);
WIRE 16 -1 (-925 -1500)(175 -1500);
FORCEPROP 2 LAST SIG_NAME SMB_LM75_2_3V3AUX_SCL
J 0
(-935 -1490);
DISPLAY 0.638298 (-935 -1490);
PAINT WHITE (-935 -1490);
WIRE 16 -1 (-925 -1350)(175 -1350);
FORCEPROP 2 LAST SIG_NAME SMB_LM75_2_3V3AUX_SDA
J 0
(-935 -1340);
DISPLAY 0.638298 (-935 -1340);
PAINT WHITE (-935 -1340);
WIRE 16 -1 (-975 -2975)(125 -2975);
FORCEPROP 2 LAST SIG_NAME SMB_LM75_3_3V3AUX_SCL
J 0
(-985 -2965);
DISPLAY 0.638298 (-985 -2965);
PAINT WHITE (-985 -2965);
WIRE 16 -1 (325 -3125)(1650 -3125);
FORCEPROP 2 LAST SIG_NAME FM_LM75_3_ALERT_N
J 0
(815 -3115);
DISPLAY 0.638298 (815 -3115);
PAINT WHITE (815 -3115);
FORCEPROP 2 LASTPROP $XRERR UNIQUE?
J 0
(575 -3115);
DISPLAY 0.638298 (575 -3115);
PAINT MONO (575 -3115);
DISPLAY INVISIBLE (575 -3115);
WIRE 16 -1 (325 -2825)(1650 -2825);
FORCEPROP 2 LAST SIG_NAME SMB_LM75_3_3V3AUX_SDA_R1
J 0
(815 -2815);
DISPLAY 0.638298 (815 -2815);
PAINT WHITE (815 -2815);
FORCEPROP 2 LASTPROP $XRERR UNIQUE?
J 0
(575 -2815);
DISPLAY 0.638298 (575 -2815);
PAINT MONO (575 -2815);
DISPLAY INVISIBLE (575 -2815);
WIRE 16 -1 (325 -2975)(1650 -2975);
FORCEPROP 2 LAST SIG_NAME SMB_LM75_3_3V3AUX_SCL_R1
J 0
(815 -2965);
DISPLAY 0.638298 (815 -2965);
PAINT WHITE (815 -2965);
FORCEPROP 2 LASTPROP $XRERR UNIQUE?
J 0
(575 -2965);
DISPLAY 0.638298 (575 -2965);
PAINT MONO (575 -2965);
DISPLAY INVISIBLE (575 -2965);
WIRE 16 -1 (-975 -2825)(125 -2825);
FORCEPROP 2 LAST SIG_NAME SMB_LM75_3_3V3AUX_SDA
J 0
(-985 -2815);
DISPLAY 0.638298 (-985 -2815);
PAINT WHITE (-985 -2815);
WIRE 16 -1 (375 -1350)(1700 -1350);
FORCEPROP 2 LAST SIG_NAME SMB_LM75_2_3V3AUX_SDA_R1
J 0
(865 -1340);
DISPLAY 0.638298 (865 -1340);
PAINT WHITE (865 -1340);
FORCEPROP 2 LASTPROP $XRERR UNIQUE?
J 0
(625 -1340);
DISPLAY 0.638298 (625 -1340);
PAINT MONO (625 -1340);
DISPLAY INVISIBLE (625 -1340);
WIRE 16 -1 (400 -25)(1725 -25);
FORCEPROP 2 LAST SIG_NAME SMB_LM75_1_3V3AUX_SCL_R1
J 0
(890 -15);
DISPLAY 0.638298 (890 -15);
PAINT WHITE (890 -15);
FORCEPROP 2 LASTPROP $XRERR UNIQUE?
J 0
(650 -15);
DISPLAY 0.638298 (650 -15);
PAINT MONO (650 -15);
DISPLAY INVISIBLE (650 -15);
WIRE 16 -1 (-900 125)(200 125);
FORCEPROP 2 LAST SIG_NAME SMB_LM75_1_3V3AUX_SDA
J 0
(-910 135);
DISPLAY 0.638298 (-910 135);
PAINT WHITE (-910 135);
WIRE 16 -1 (-850 1300)(-200 1300);
FORCEPROP 2 LAST SIG_NAME FM_THERMAL_ALERT_N
J 0
(-860 1310);
DISPLAY 0.638298 (-860 1310);
PAINT WHITE (-860 1310);
WIRE 16 -1 (-200 1300)(250 1300);
WIRE 16 -1 (-200 1700)(-200 1300);
WIRE 16 -1 (-850 1600)(250 1600);
FORCEPROP 2 LAST SIG_NAME SMB_LM75_0_3V3AUX_SDA
J 0
(-860 1610);
DISPLAY 0.638298 (-860 1610);
PAINT WHITE (-860 1610);
WIRE 16 -1 (-925 -175)(-250 -175);
FORCEPROP 2 LAST SIG_NAME FM_THERMAL_ALERT_N
J 0
(-910 -165);
DISPLAY 0.638298 (-910 -165);
PAINT WHITE (-910 -165);
WIRE 16 -1 (-250 -175)(200 -175);
WIRE 16 -1 (-250 225)(-250 -175);
WIRE 16 -1 (-925 -1650)(-250 -1650);
FORCEPROP 2 LAST SIG_NAME FM_THERMAL_ALERT_N
J 0
(-935 -1640);
DISPLAY 0.638298 (-935 -1640);
PAINT WHITE (-935 -1640);
WIRE 16 -1 (-250 -1650)(175 -1650);
WIRE 16 -1 (-250 -1275)(-250 -1650);
WIRE 16 -1 (-1000 -3125)(-350 -3125);
FORCEPROP 2 LAST SIG_NAME FM_THERMAL_ALERT_N
J 0
(-985 -3115);
DISPLAY 0.638298 (-985 -3115);
PAINT WHITE (-985 -3115);
WIRE 16 -1 (-350 -3125)(125 -3125);
WIRE 16 -1 (-350 -2725)(-350 -3125);
DOT 1 (2600 2125);
DOT 1 (4325 -2550);
DOT 1 (4075 -2550);
DOT 1 (4325 -2975);
DOT 1 (2475 -2300);
DOT 1 (2525 -825);
DOT 1 (4375 -1500);
DOT 1 (4125 -1075);
DOT 1 (4375 -1075);
DOT 1 (4400 -25);
DOT 1 (4150 400);
DOT 1 (4400 400);
DOT 1 (2550 650);
DOT 1 (4450 1875);
DOT 1 (4200 1875);
DOT 1 (4450 1450);
DOT 1 (-200 1300);
DOT 1 (3950 1150);
DOT 1 (4200 1300);
DOT 1 (-250 -175);
DOT 1 (3900 -325);
DOT 1 (4150 -175);
DOT 1 (-250 -1650);
DOT 1 (3875 -1800);
DOT 1 (4125 -1650);
DOT 1 (-350 -3125);
DOT 1 (3825 -3275);
DOT 1 (4075 -3125);
FORCENOTE
ADDRESS : 0X90 (8-BIT) / 0X48 (7-BIT)
(825 925) 0;
DISPLAY LEFT (825 925);
DISPLAY 1.340425 (825 925);
PAINT WHITE (825 925);
FORCENOTE
ADDRESS : 0X90 (8-BIT) / 0X48 (7-BIT)
(900 -525) 0;
DISPLAY LEFT (900 -525);
DISPLAY 1.340425 (900 -525);
PAINT WHITE (900 -525);
FORCENOTE
ADDRESS : 0X90 (8-BIT) / 0X48 (7-BIT)
(825 -3525) 0;
DISPLAY LEFT (825 -3525);
DISPLAY 1.340425 (825 -3525);
PAINT WHITE (825 -3525);
FORCENOTE
ADDRESS : 0X90 (8-BIT) / 0X48 (7-BIT)
(900 -2025) 0;
DISPLAY LEFT (900 -2025);
DISPLAY 1.340425 (900 -2025);
PAINT WHITE (900 -2025);
QUIT
